FILE_TYPE = MACRO_DRAWING;
SET COLOR_WIRE YELLOW;
SET COLOR_PROP ORANGE;
SET COLOR_DOT WHITE;
SET COLOR_ARC YELLOW;
SET COLOR_BODY GREEN;
SET COLOR_NOTE PURPLE;
SET PROP_DISPLAY VALUE;
SET PAGE_NUMBER P352;
FORCEADD OFFPAGE..1
(-2575 1600);
FORCEPROP 2 LAST $XR0 25 
J 0
(-2796 1600);
DISPLAY 0.638298 (-2796 1600);
PAINT MONO (-2796 1600);
FORCEPROP 2 LAST CDS_LIB standard
J 0
(-2575 1600);
DISPLAY INVISIBLE (-2575 1600);
FORCEPROP 1 LAST OFFPAGE TRUE
J 0
(-2250 1475);
DISPLAY 0.872340 (-2250 1475);
DISPLAY INVISIBLE (-2250 1475);
FORCEPROP 1 LAST COMMENT_BODY TRUE
J 0
(-2450 1500);
DISPLAY 0.872340 (-2450 1500);
PAINT GREEN (-2450 1500);
DISPLAY INVISIBLE (-2450 1500);
FORCEPROP 2 LAST PATH I1
J 0
(-2825 1650);
DISPLAY 1.021277 (-2825 1650);
DISPLAY INVISIBLE (-2825 1650);
FORCEADD TAP..1
R 2
(-1375 175);
FORCEPROP 3 LASTPIN (-1325 175) SIG_NAME P5E_CPU0_P2_TX_DN<0>
J 0
(-1315 185);
DISPLAY 0.659574 (-1315 185);
PAINT MONO (-1315 185);
DISPLAY INVISIBLE (-1315 185);
FORCEPROP 1 LASTPIN (-1325 175) BN 0
J 2
(-1313 183);
DISPLAY 0.680851 (-1313 183);
PAINT GREEN (-1313 183);
FORCEPROP 2 LAST CDS_LIB standard
J 0
(-1375 175);
DISPLAY INVISIBLE (-1375 175);
FORCEPROP 1 LAST BODY_TYPE PLUMBING
J 2
(-1375 225);
DISPLAY 0.872340 (-1375 225);
PAINT GREEN (-1375 225);
DISPLAY INVISIBLE (-1375 225);
FORCEPROP 1 LAST HDL_TAP TRUE
J 2
(-1700 50);
DISPLAY 0.872340 (-1700 50);
DISPLAY INVISIBLE (-1700 50);
FORCEPROP 1 LAST PATH I10
J 2
(-1373 175);
DISPLAY 0.872340 (-1373 175);
PAINT GREEN (-1373 175);
DISPLAY INVISIBLE (-1373 175);
FORCEADD TAP..1
(100 2700);
FORCEPROP 3 LASTPIN (50 2700) SIG_NAME P5E_CPU0_P2_TX_C_DP<11>
J 0
(60 2710);
DISPLAY 0.659574 (60 2710);
PAINT MONO (60 2710);
DISPLAY INVISIBLE (60 2710);
FORCEPROP 1 LASTPIN (50 2700) BN 11
J 0
(38 2708);
DISPLAY 0.680851 (38 2708);
PAINT GREEN (38 2708);
FORCEPROP 2 LAST CDS_LIB standard
J 0
(100 2700);
DISPLAY INVISIBLE (100 2700);
FORCEPROP 1 LAST BODY_TYPE PLUMBING
J 0
(100 2750);
DISPLAY 0.872340 (100 2750);
PAINT GREEN (100 2750);
DISPLAY INVISIBLE (100 2750);
FORCEPROP 1 LAST HDL_TAP TRUE
J 0
(425 2575);
DISPLAY 0.872340 (425 2575);
DISPLAY INVISIBLE (425 2575);
FORCEPROP 1 LAST PATH I100
J 0
(98 2700);
DISPLAY 0.872340 (98 2700);
PAINT GREEN (98 2700);
DISPLAY INVISIBLE (98 2700);
FORCEADD TAP..1
(100 2900);
FORCEPROP 3 LASTPIN (50 2900) SIG_NAME P5E_CPU0_P2_TX_C_DP<12>
J 0
(60 2910);
DISPLAY 0.659574 (60 2910);
PAINT MONO (60 2910);
DISPLAY INVISIBLE (60 2910);
FORCEPROP 1 LASTPIN (50 2900) BN 12
J 0
(38 2908);
DISPLAY 0.680851 (38 2908);
PAINT GREEN (38 2908);
FORCEPROP 2 LAST CDS_LIB standard
J 0
(100 2900);
DISPLAY INVISIBLE (100 2900);
FORCEPROP 1 LAST BODY_TYPE PLUMBING
J 0
(100 2950);
DISPLAY 0.872340 (100 2950);
PAINT GREEN (100 2950);
DISPLAY INVISIBLE (100 2950);
FORCEPROP 1 LAST HDL_TAP TRUE
J 0
(425 2775);
DISPLAY 0.872340 (425 2775);
DISPLAY INVISIBLE (425 2775);
FORCEPROP 1 LAST PATH I101
J 0
(98 2900);
DISPLAY 0.872340 (98 2900);
PAINT GREEN (98 2900);
DISPLAY INVISIBLE (98 2900);
FORCEADD TAP..1
(100 3100);
FORCEPROP 3 LASTPIN (50 3100) SIG_NAME P5E_CPU0_P2_TX_C_DP<13>
J 0
(60 3110);
DISPLAY 0.659574 (60 3110);
PAINT MONO (60 3110);
DISPLAY INVISIBLE (60 3110);
FORCEPROP 1 LASTPIN (50 3100) BN 13
J 0
(38 3108);
DISPLAY 0.680851 (38 3108);
PAINT GREEN (38 3108);
FORCEPROP 2 LAST CDS_LIB standard
J 0
(100 3100);
DISPLAY INVISIBLE (100 3100);
FORCEPROP 1 LAST BODY_TYPE PLUMBING
J 0
(100 3150);
DISPLAY 0.872340 (100 3150);
PAINT GREEN (100 3150);
DISPLAY INVISIBLE (100 3150);
FORCEPROP 1 LAST HDL_TAP TRUE
J 0
(425 2975);
DISPLAY 0.872340 (425 2975);
DISPLAY INVISIBLE (425 2975);
FORCEPROP 1 LAST PATH I102
J 0
(98 3100);
DISPLAY 0.872340 (98 3100);
PAINT GREEN (98 3100);
DISPLAY INVISIBLE (98 3100);
FORCEADD TAP..1
(100 3300);
FORCEPROP 3 LASTPIN (50 3300) SIG_NAME P5E_CPU0_P2_TX_C_DP<14>
J 0
(60 3310);
DISPLAY 0.659574 (60 3310);
PAINT MONO (60 3310);
DISPLAY INVISIBLE (60 3310);
FORCEPROP 1 LASTPIN (50 3300) BN 14
J 0
(38 3308);
DISPLAY 0.680851 (38 3308);
PAINT GREEN (38 3308);
FORCEPROP 2 LAST CDS_LIB standard
J 0
(100 3300);
DISPLAY INVISIBLE (100 3300);
FORCEPROP 1 LAST BODY_TYPE PLUMBING
J 0
(100 3350);
DISPLAY 0.872340 (100 3350);
PAINT GREEN (100 3350);
DISPLAY INVISIBLE (100 3350);
FORCEPROP 1 LAST HDL_TAP TRUE
J 0
(425 3175);
DISPLAY 0.872340 (425 3175);
DISPLAY INVISIBLE (425 3175);
FORCEPROP 1 LAST PATH I103
J 0
(98 3300);
DISPLAY 0.872340 (98 3300);
PAINT GREEN (98 3300);
DISPLAY INVISIBLE (98 3300);
FORCEADD TAP..1
(100 3500);
FORCEPROP 3 LASTPIN (50 3500) SIG_NAME P5E_CPU0_P2_TX_C_DP<15>
J 0
(60 3510);
DISPLAY 0.659574 (60 3510);
PAINT MONO (60 3510);
DISPLAY INVISIBLE (60 3510);
FORCEPROP 1 LASTPIN (50 3500) BN 15
J 0
(38 3508);
DISPLAY 0.680851 (38 3508);
PAINT GREEN (38 3508);
FORCEPROP 2 LAST CDS_LIB standard
J 0
(100 3500);
DISPLAY INVISIBLE (100 3500);
FORCEPROP 1 LAST BODY_TYPE PLUMBING
J 0
(100 3550);
DISPLAY 0.872340 (100 3550);
PAINT GREEN (100 3550);
DISPLAY INVISIBLE (100 3550);
FORCEPROP 1 LAST HDL_TAP TRUE
J 0
(425 3375);
DISPLAY 0.872340 (425 3375);
DISPLAY INVISIBLE (425 3375);
FORCEPROP 1 LAST PATH I104
J 0
(98 3500);
DISPLAY 0.872340 (98 3500);
PAINT GREEN (98 3500);
DISPLAY INVISIBLE (98 3500);
FORCEADD OFFPAGE..2
(1100 3525);
FORCEPROP 2 LAST $XR0 295 
J 0
(1289 3525);
DISPLAY 0.638298 (1289 3525);
PAINT MONO (1289 3525);
FORCEPROP 2 LAST CDS_LIB standard
J 0
(1100 3525);
DISPLAY INVISIBLE (1100 3525);
FORCEPROP 1 LAST OFFPAGE TRUE
J 0
(1425 3400);
DISPLAY 0.872340 (1425 3400);
DISPLAY INVISIBLE (1425 3400);
FORCEPROP 1 LAST COMMENT_BODY TRUE
J 0
(1055 3430);
DISPLAY 0.872340 (1055 3430);
PAINT GREEN (1055 3430);
DISPLAY INVISIBLE (1055 3430);
FORCEPROP 2 LAST PATH I105
J 0
(1300 3575);
DISPLAY 1.021277 (1300 3575);
DISPLAY INVISIBLE (1300 3575);
FORCEADD OFFPAGE..2
(1100 3575);
FORCEPROP 2 LAST $XR0 295 
J 0
(1289 3575);
DISPLAY 0.638298 (1289 3575);
PAINT MONO (1289 3575);
FORCEPROP 2 LAST CDS_LIB standard
J 0
(1100 3575);
DISPLAY INVISIBLE (1100 3575);
FORCEPROP 1 LAST OFFPAGE TRUE
J 0
(1425 3450);
DISPLAY 0.872340 (1425 3450);
DISPLAY INVISIBLE (1425 3450);
FORCEPROP 1 LAST COMMENT_BODY TRUE
J 0
(1055 3480);
DISPLAY 0.872340 (1055 3480);
PAINT GREEN (1055 3480);
DISPLAY INVISIBLE (1055 3480);
FORCEPROP 2 LAST PATH I106
J 0
(1300 3625);
DISPLAY 1.021277 (1300 3625);
DISPLAY INVISIBLE (1300 3625);
FORCEADD OFFPAGE..1
(1900 3525);
FORCEPROP 2 LAST $XR0 25 
J 0
(1679 3525);
DISPLAY 0.638298 (1679 3525);
PAINT MONO (1679 3525);
FORCEPROP 2 LAST CDS_LIB standard
J 0
(1900 3525);
DISPLAY INVISIBLE (1900 3525);
FORCEPROP 1 LAST OFFPAGE TRUE
J 0
(2225 3400);
DISPLAY 0.872340 (2225 3400);
DISPLAY INVISIBLE (2225 3400);
FORCEPROP 1 LAST COMMENT_BODY TRUE
J 0
(2025 3425);
DISPLAY 0.872340 (2025 3425);
PAINT GREEN (2025 3425);
DISPLAY INVISIBLE (2025 3425);
FORCEPROP 2 LAST PATH I107
J 0
(1650 3575);
DISPLAY 1.021277 (1650 3575);
DISPLAY INVISIBLE (1650 3575);
FORCEADD OFFPAGE..1
(1900 3575);
FORCEPROP 2 LAST $XR0 25 
J 0
(1679 3575);
DISPLAY 0.638298 (1679 3575);
PAINT MONO (1679 3575);
FORCEPROP 2 LAST CDS_LIB standard
J 0
(1900 3575);
DISPLAY INVISIBLE (1900 3575);
FORCEPROP 1 LAST OFFPAGE TRUE
J 0
(2225 3450);
DISPLAY 0.872340 (2225 3450);
DISPLAY INVISIBLE (2225 3450);
FORCEPROP 1 LAST COMMENT_BODY TRUE
J 0
(2025 3475);
DISPLAY 0.872340 (2025 3475);
PAINT GREEN (2025 3475);
DISPLAY INVISIBLE (2025 3475);
FORCEPROP 2 LAST PATH I108
J 0
(1650 3625);
DISPLAY 1.021277 (1650 3625);
DISPLAY INVISIBLE (1650 3625);
FORCEADD TAP..1
R 2
(2850 125);
FORCEPROP 3 LASTPIN (2900 125) SIG_NAME P5E_CPU0_P3_TX_DP<0>
J 0
(2910 135);
DISPLAY 0.659574 (2910 135);
PAINT MONO (2910 135);
DISPLAY INVISIBLE (2910 135);
FORCEPROP 1 LASTPIN (2900 125) BN 0
J 2
(2912 133);
DISPLAY 0.680851 (2912 133);
PAINT GREEN (2912 133);
FORCEPROP 2 LAST CDS_LIB standard
J 0
(2850 125);
DISPLAY INVISIBLE (2850 125);
FORCEPROP 1 LAST BODY_TYPE PLUMBING
J 2
(2850 175);
DISPLAY 0.872340 (2850 175);
PAINT GREEN (2850 175);
DISPLAY INVISIBLE (2850 175);
FORCEPROP 1 LAST HDL_TAP TRUE
J 2
(2525 0);
DISPLAY 0.872340 (2525 0);
DISPLAY INVISIBLE (2525 0);
FORCEPROP 1 LAST PATH I109
J 2
(2852 125);
DISPLAY 0.872340 (2852 125);
PAINT GREEN (2852 125);
DISPLAY INVISIBLE (2852 125);
FORCEADD TAP..1
R 2
(-1375 375);
FORCEPROP 3 LASTPIN (-1325 375) SIG_NAME P5E_CPU0_P2_TX_DN<1>
J 0
(-1315 385);
DISPLAY 0.659574 (-1315 385);
PAINT MONO (-1315 385);
DISPLAY INVISIBLE (-1315 385);
FORCEPROP 1 LASTPIN (-1325 375) BN 1
J 2
(-1313 383);
DISPLAY 0.680851 (-1313 383);
PAINT GREEN (-1313 383);
FORCEPROP 2 LAST CDS_LIB standard
J 0
(-1375 375);
DISPLAY INVISIBLE (-1375 375);
FORCEPROP 1 LAST BODY_TYPE PLUMBING
J 2
(-1375 425);
DISPLAY 0.872340 (-1375 425);
PAINT GREEN (-1375 425);
DISPLAY INVISIBLE (-1375 425);
FORCEPROP 1 LAST HDL_TAP TRUE
J 2
(-1700 250);
DISPLAY 0.872340 (-1700 250);
DISPLAY INVISIBLE (-1700 250);
FORCEPROP 1 LAST PATH I11
J 2
(-1373 375);
DISPLAY 0.872340 (-1373 375);
PAINT GREEN (-1373 375);
DISPLAY INVISIBLE (-1373 375);
FORCEADD TAP..1
R 2
(2850 325);
FORCEPROP 3 LASTPIN (2900 325) SIG_NAME P5E_CPU0_P3_TX_DP<1>
J 0
(2910 335);
DISPLAY 0.659574 (2910 335);
PAINT MONO (2910 335);
DISPLAY INVISIBLE (2910 335);
FORCEPROP 1 LASTPIN (2900 325) BN 1
J 2
(2912 333);
DISPLAY 0.680851 (2912 333);
PAINT GREEN (2912 333);
FORCEPROP 2 LAST CDS_LIB standard
J 0
(2850 325);
DISPLAY INVISIBLE (2850 325);
FORCEPROP 1 LAST BODY_TYPE PLUMBING
J 2
(2850 375);
DISPLAY 0.872340 (2850 375);
PAINT GREEN (2850 375);
DISPLAY INVISIBLE (2850 375);
FORCEPROP 1 LAST HDL_TAP TRUE
J 2
(2525 200);
DISPLAY 0.872340 (2525 200);
DISPLAY INVISIBLE (2525 200);
FORCEPROP 1 LAST PATH I110
J 2
(2852 325);
DISPLAY 0.872340 (2852 325);
PAINT GREEN (2852 325);
DISPLAY INVISIBLE (2852 325);
FORCEADD TAP..1
R 2
(2850 525);
FORCEPROP 3 LASTPIN (2900 525) SIG_NAME P5E_CPU0_P3_TX_DP<2>
J 0
(2910 535);
DISPLAY 0.659574 (2910 535);
PAINT MONO (2910 535);
DISPLAY INVISIBLE (2910 535);
FORCEPROP 1 LASTPIN (2900 525) BN 2
J 2
(2912 533);
DISPLAY 0.680851 (2912 533);
PAINT GREEN (2912 533);
FORCEPROP 2 LAST CDS_LIB standard
J 0
(2850 525);
DISPLAY INVISIBLE (2850 525);
FORCEPROP 1 LAST BODY_TYPE PLUMBING
J 2
(2850 575);
DISPLAY 0.872340 (2850 575);
PAINT GREEN (2850 575);
DISPLAY INVISIBLE (2850 575);
FORCEPROP 1 LAST HDL_TAP TRUE
J 2
(2525 400);
DISPLAY 0.872340 (2525 400);
DISPLAY INVISIBLE (2525 400);
FORCEPROP 1 LAST PATH I111
J 2
(2852 525);
DISPLAY 0.872340 (2852 525);
PAINT GREEN (2852 525);
DISPLAY INVISIBLE (2852 525);
FORCEADD TAP..1
R 2
(2850 725);
FORCEPROP 3 LASTPIN (2900 725) SIG_NAME P5E_CPU0_P3_TX_DP<3>
J 0
(2910 735);
DISPLAY 0.659574 (2910 735);
PAINT MONO (2910 735);
DISPLAY INVISIBLE (2910 735);
FORCEPROP 1 LASTPIN (2900 725) BN 3
J 2
(2912 733);
DISPLAY 0.680851 (2912 733);
PAINT GREEN (2912 733);
FORCEPROP 2 LAST CDS_LIB standard
J 0
(2850 725);
DISPLAY INVISIBLE (2850 725);
FORCEPROP 1 LAST BODY_TYPE PLUMBING
J 2
(2850 775);
DISPLAY 0.872340 (2850 775);
PAINT GREEN (2850 775);
DISPLAY INVISIBLE (2850 775);
FORCEPROP 1 LAST HDL_TAP TRUE
J 2
(2525 600);
DISPLAY 0.872340 (2525 600);
DISPLAY INVISIBLE (2525 600);
FORCEPROP 1 LAST PATH I112
J 2
(2852 725);
DISPLAY 0.872340 (2852 725);
PAINT GREEN (2852 725);
DISPLAY INVISIBLE (2852 725);
FORCEADD TAP..1
R 2
(2850 925);
FORCEPROP 3 LASTPIN (2900 925) SIG_NAME P5E_CPU0_P3_TX_DP<4>
J 0
(2910 935);
DISPLAY 0.659574 (2910 935);
PAINT MONO (2910 935);
DISPLAY INVISIBLE (2910 935);
FORCEPROP 1 LASTPIN (2900 925) BN 4
J 2
(2912 933);
DISPLAY 0.680851 (2912 933);
PAINT GREEN (2912 933);
FORCEPROP 2 LAST CDS_LIB standard
J 0
(2850 925);
DISPLAY INVISIBLE (2850 925);
FORCEPROP 1 LAST BODY_TYPE PLUMBING
J 2
(2850 975);
DISPLAY 0.872340 (2850 975);
PAINT GREEN (2850 975);
DISPLAY INVISIBLE (2850 975);
FORCEPROP 1 LAST HDL_TAP TRUE
J 2
(2525 800);
DISPLAY 0.872340 (2525 800);
DISPLAY INVISIBLE (2525 800);
FORCEPROP 1 LAST PATH I113
J 2
(2852 925);
DISPLAY 0.872340 (2852 925);
PAINT GREEN (2852 925);
DISPLAY INVISIBLE (2852 925);
FORCEADD TAP..1
R 2
(2850 1325);
FORCEPROP 3 LASTPIN (2900 1325) SIG_NAME P5E_CPU0_P3_TX_DP<6>
J 0
(2910 1335);
DISPLAY 0.659574 (2910 1335);
PAINT MONO (2910 1335);
DISPLAY INVISIBLE (2910 1335);
FORCEPROP 1 LASTPIN (2900 1325) BN 6
J 2
(2912 1333);
DISPLAY 0.680851 (2912 1333);
PAINT GREEN (2912 1333);
FORCEPROP 2 LAST CDS_LIB standard
J 0
(2850 1325);
DISPLAY INVISIBLE (2850 1325);
FORCEPROP 1 LAST BODY_TYPE PLUMBING
J 2
(2850 1375);
DISPLAY 0.872340 (2850 1375);
PAINT GREEN (2850 1375);
DISPLAY INVISIBLE (2850 1375);
FORCEPROP 1 LAST HDL_TAP TRUE
J 2
(2525 1200);
DISPLAY 0.872340 (2525 1200);
DISPLAY INVISIBLE (2525 1200);
FORCEPROP 1 LAST PATH I114
J 2
(2852 1325);
DISPLAY 0.872340 (2852 1325);
PAINT GREEN (2852 1325);
DISPLAY INVISIBLE (2852 1325);
FORCEADD TAP..1
R 2
(2850 1525);
FORCEPROP 3 LASTPIN (2900 1525) SIG_NAME P5E_CPU0_P3_TX_DP<7>
J 0
(2910 1535);
DISPLAY 0.659574 (2910 1535);
PAINT MONO (2910 1535);
DISPLAY INVISIBLE (2910 1535);
FORCEPROP 1 LASTPIN (2900 1525) BN 7
J 2
(2912 1533);
DISPLAY 0.680851 (2912 1533);
PAINT GREEN (2912 1533);
FORCEPROP 2 LAST CDS_LIB standard
J 0
(2850 1525);
DISPLAY INVISIBLE (2850 1525);
FORCEPROP 1 LAST BODY_TYPE PLUMBING
J 2
(2850 1575);
DISPLAY 0.872340 (2850 1575);
PAINT GREEN (2850 1575);
DISPLAY INVISIBLE (2850 1575);
FORCEPROP 1 LAST HDL_TAP TRUE
J 2
(2525 1400);
DISPLAY 0.872340 (2525 1400);
DISPLAY INVISIBLE (2525 1400);
FORCEPROP 1 LAST PATH I115
J 2
(2852 1525);
DISPLAY 0.872340 (2852 1525);
PAINT GREEN (2852 1525);
DISPLAY INVISIBLE (2852 1525);
FORCEADD TAP..1
R 2
(3100 175);
FORCEPROP 3 LASTPIN (3150 175) SIG_NAME P5E_CPU0_P3_TX_DN<0>
J 0
(3160 185);
DISPLAY 0.659574 (3160 185);
PAINT MONO (3160 185);
DISPLAY INVISIBLE (3160 185);
FORCEPROP 1 LASTPIN (3150 175) BN 0
J 2
(3162 183);
DISPLAY 0.680851 (3162 183);
PAINT GREEN (3162 183);
FORCEPROP 2 LAST CDS_LIB standard
J 0
(3100 175);
DISPLAY INVISIBLE (3100 175);
FORCEPROP 1 LAST BODY_TYPE PLUMBING
J 2
(3100 225);
DISPLAY 0.872340 (3100 225);
PAINT GREEN (3100 225);
DISPLAY INVISIBLE (3100 225);
FORCEPROP 1 LAST HDL_TAP TRUE
J 2
(2775 50);
DISPLAY 0.872340 (2775 50);
DISPLAY INVISIBLE (2775 50);
FORCEPROP 1 LAST PATH I116
J 2
(3102 175);
DISPLAY 0.872340 (3102 175);
PAINT GREEN (3102 175);
DISPLAY INVISIBLE (3102 175);
FORCEADD TAP..1
R 2
(3100 375);
FORCEPROP 3 LASTPIN (3150 375) SIG_NAME P5E_CPU0_P3_TX_DN<1>
J 0
(3160 385);
DISPLAY 0.659574 (3160 385);
PAINT MONO (3160 385);
DISPLAY INVISIBLE (3160 385);
FORCEPROP 1 LASTPIN (3150 375) BN 1
J 2
(3162 383);
DISPLAY 0.680851 (3162 383);
PAINT GREEN (3162 383);
FORCEPROP 2 LAST CDS_LIB standard
J 0
(3100 375);
DISPLAY INVISIBLE (3100 375);
FORCEPROP 1 LAST BODY_TYPE PLUMBING
J 2
(3100 425);
DISPLAY 0.872340 (3100 425);
PAINT GREEN (3100 425);
DISPLAY INVISIBLE (3100 425);
FORCEPROP 1 LAST HDL_TAP TRUE
J 2
(2775 250);
DISPLAY 0.872340 (2775 250);
DISPLAY INVISIBLE (2775 250);
FORCEPROP 1 LAST PATH I117
J 2
(3102 375);
DISPLAY 0.872340 (3102 375);
PAINT GREEN (3102 375);
DISPLAY INVISIBLE (3102 375);
FORCEADD TAP..1
R 2
(3100 575);
FORCEPROP 3 LASTPIN (3150 575) SIG_NAME P5E_CPU0_P3_TX_DN<2>
J 0
(3160 585);
DISPLAY 0.659574 (3160 585);
PAINT MONO (3160 585);
DISPLAY INVISIBLE (3160 585);
FORCEPROP 1 LASTPIN (3150 575) BN 2
J 2
(3162 583);
DISPLAY 0.680851 (3162 583);
PAINT GREEN (3162 583);
FORCEPROP 2 LAST CDS_LIB standard
J 0
(3100 575);
DISPLAY INVISIBLE (3100 575);
FORCEPROP 1 LAST BODY_TYPE PLUMBING
J 2
(3100 625);
DISPLAY 0.872340 (3100 625);
PAINT GREEN (3100 625);
DISPLAY INVISIBLE (3100 625);
FORCEPROP 1 LAST HDL_TAP TRUE
J 2
(2775 450);
DISPLAY 0.872340 (2775 450);
DISPLAY INVISIBLE (2775 450);
FORCEPROP 1 LAST PATH I118
J 2
(3102 575);
DISPLAY 0.872340 (3102 575);
PAINT GREEN (3102 575);
DISPLAY INVISIBLE (3102 575);
FORCEADD TAP..1
R 2
(3100 775);
FORCEPROP 3 LASTPIN (3150 775) SIG_NAME P5E_CPU0_P3_TX_DN<3>
J 0
(3160 785);
DISPLAY 0.659574 (3160 785);
PAINT MONO (3160 785);
DISPLAY INVISIBLE (3160 785);
FORCEPROP 1 LASTPIN (3150 775) BN 3
J 2
(3162 783);
DISPLAY 0.680851 (3162 783);
PAINT GREEN (3162 783);
FORCEPROP 2 LAST CDS_LIB standard
J 0
(3100 775);
DISPLAY INVISIBLE (3100 775);
FORCEPROP 1 LAST BODY_TYPE PLUMBING
J 2
(3100 825);
DISPLAY 0.872340 (3100 825);
PAINT GREEN (3100 825);
DISPLAY INVISIBLE (3100 825);
FORCEPROP 1 LAST HDL_TAP TRUE
J 2
(2775 650);
DISPLAY 0.872340 (2775 650);
DISPLAY INVISIBLE (2775 650);
FORCEPROP 1 LAST PATH I119
J 2
(3102 775);
DISPLAY 0.872340 (3102 775);
PAINT GREEN (3102 775);
DISPLAY INVISIBLE (3102 775);
FORCEADD TAP..1
R 2
(-1375 575);
FORCEPROP 3 LASTPIN (-1325 575) SIG_NAME P5E_CPU0_P2_TX_DN<2>
J 0
(-1315 585);
DISPLAY 0.659574 (-1315 585);
PAINT MONO (-1315 585);
DISPLAY INVISIBLE (-1315 585);
FORCEPROP 1 LASTPIN (-1325 575) BN 2
J 2
(-1313 583);
DISPLAY 0.680851 (-1313 583);
PAINT GREEN (-1313 583);
FORCEPROP 2 LAST CDS_LIB standard
J 0
(-1375 575);
DISPLAY INVISIBLE (-1375 575);
FORCEPROP 1 LAST BODY_TYPE PLUMBING
J 2
(-1375 625);
DISPLAY 0.872340 (-1375 625);
PAINT GREEN (-1375 625);
DISPLAY INVISIBLE (-1375 625);
FORCEPROP 1 LAST HDL_TAP TRUE
J 2
(-1700 450);
DISPLAY 0.872340 (-1700 450);
DISPLAY INVISIBLE (-1700 450);
FORCEPROP 1 LAST PATH I12
J 2
(-1373 575);
DISPLAY 0.872340 (-1373 575);
PAINT GREEN (-1373 575);
DISPLAY INVISIBLE (-1373 575);
FORCEADD Q_CAP_DIFFBUS..2
R 2
(3825 125);
FORCEPROP 1 LAST LOCATION C901
J 2
(4059 142);
DISPLAY 0.723404 (4059 142);
PAINT GREEN (4059 142);
FORCEPROP 2 LAST $SEC 1
J 2
(4000 200);
DISPLAY 0.680851 (4000 200);
PAINT MONO (4000 200);
DISPLAY INVISIBLE (4000 200);
FORCEPROP 2 LAST CDS_SEC 1
J 2
(4000 200);
DISPLAY 0.680851 (4000 200);
DISPLAY INVISIBLE (4000 200);
FORCEPROP 2 LASTPIN (3900 125) $PN 1
J 0
(3910 135);
DISPLAY 0.808511 (3910 135);
FORCEPROP 2 LASTPIN (3750 125) $PN 2
J 2
(3740 135);
DISPLAY 0.808511 (3740 135);
FORCEPROP 2 LAST VALUE DIFF BUS_0.22UF
J 2
(3675 125);
DISPLAY 0.553191 (3675 125);
FORCEPROP 1 LAST PIN_NAMES_ROTATE TRUE
J 2
(3825 125);
DISPLAY 0.489362 (3825 125);
PAINT GREEN (3825 125);
DISPLAY INVISIBLE (3825 125);
FORCEPROP 2 LAST CDS_LIB pure_quanta
J 2
(3825 125);
DISPLAY INVISIBLE (3825 125);
FORCEPROP 1 LAST CDS_LMAN_SYM_OUTLINE -25,50,25,-50
J 2
(3825 125);
DISPLAY 0.468085 (3825 125);
PAINT GREEN (3825 125);
DISPLAY INVISIBLE (3825 125);
FORCEPROP 2 LAST VOLTAGE 6.3V
J 2
(3475 175);
DISPLAY 0.553191 (3475 175);
DISPLAY INVISIBLE (3475 175);
FORCEPROP 1 LAST MATERIAL X6S
J 2
(3834 204);
DISPLAY 0.574468 (3834 204);
PAINT GREEN (3834 204);
DISPLAY INVISIBLE (3834 204);
FORCEPROP 2 LAST PACK_TYPE C0201
J 2
(3650 175);
DISPLAY 0.553191 (3650 175);
DISPLAY INVISIBLE (3650 175);
FORCEPROP 2 LAST TOLERANCE 20%
J 2
(3750 175);
DISPLAY 0.553191 (3750 175);
DISPLAY INVISIBLE (3750 175);
FORCEPROP 1 LAST PART_NUMBER SP_CH4221MEE01
J 2
(3709 213);
DISPLAY 0.574468 (3709 213);
PAINT GREEN (3709 213);
DISPLAY INVISIBLE (3709 213);
FORCEPROP 1 LAST LOCATION C901
J 0
(4075 200);
DISPLAY 1.021277 (4075 200);
DISPLAY INVISIBLE (4075 200);
FORCEPROP 1 LAST PATH I120
J 2
(3825 125);
DISPLAY 0.723404 (3825 125);
DISPLAY INVISIBLE (3825 125);
FORCEADD Q_CAP_DIFFBUS..2
R 2
(3825 175);
FORCEPROP 1 LAST LOCATION C900
J 2
(4059 192);
DISPLAY 0.723404 (4059 192);
PAINT GREEN (4059 192);
FORCEPROP 2 LAST $SEC 1
J 2
(4000 250);
DISPLAY 0.680851 (4000 250);
PAINT MONO (4000 250);
DISPLAY INVISIBLE (4000 250);
FORCEPROP 2 LAST CDS_SEC 1
J 2
(4000 250);
DISPLAY 0.680851 (4000 250);
DISPLAY INVISIBLE (4000 250);
FORCEPROP 2 LASTPIN (3900 175) $PN 1
J 0
(3910 185);
DISPLAY 0.808511 (3910 185);
FORCEPROP 2 LASTPIN (3750 175) $PN 2
J 2
(3740 185);
DISPLAY 0.808511 (3740 185);
FORCEPROP 2 LAST VALUE DIFF BUS_0.22UF
J 2
(3675 175);
DISPLAY 0.553191 (3675 175);
FORCEPROP 1 LAST PIN_NAMES_ROTATE TRUE
J 2
(3825 175);
DISPLAY 0.489362 (3825 175);
PAINT GREEN (3825 175);
DISPLAY INVISIBLE (3825 175);
FORCEPROP 2 LAST CDS_LIB pure_quanta
J 2
(3825 175);
DISPLAY INVISIBLE (3825 175);
FORCEPROP 1 LAST CDS_LMAN_SYM_OUTLINE -25,50,25,-50
J 2
(3825 175);
DISPLAY 0.468085 (3825 175);
PAINT GREEN (3825 175);
DISPLAY INVISIBLE (3825 175);
FORCEPROP 2 LAST VOLTAGE 6.3V
J 2
(3475 225);
DISPLAY 0.553191 (3475 225);
DISPLAY INVISIBLE (3475 225);
FORCEPROP 1 LAST MATERIAL X6S
J 2
(3834 254);
DISPLAY 0.574468 (3834 254);
PAINT GREEN (3834 254);
DISPLAY INVISIBLE (3834 254);
FORCEPROP 2 LAST PACK_TYPE C0201
J 2
(3650 225);
DISPLAY 0.553191 (3650 225);
DISPLAY INVISIBLE (3650 225);
FORCEPROP 2 LAST TOLERANCE 20%
J 2
(3750 225);
DISPLAY 0.553191 (3750 225);
DISPLAY INVISIBLE (3750 225);
FORCEPROP 1 LAST PART_NUMBER SP_CH4221MEE01
J 2
(3709 263);
DISPLAY 0.574468 (3709 263);
PAINT GREEN (3709 263);
DISPLAY INVISIBLE (3709 263);
FORCEPROP 1 LAST LOCATION C900
J 0
(4075 250);
DISPLAY 1.021277 (4075 250);
DISPLAY INVISIBLE (4075 250);
FORCEPROP 1 LAST PATH I121
J 2
(3825 175);
DISPLAY 0.723404 (3825 175);
DISPLAY INVISIBLE (3825 175);
FORCEADD Q_CAP_DIFFBUS..2
R 2
(3825 325);
FORCEPROP 1 LAST LOCATION C899
J 2
(4059 342);
DISPLAY 0.723404 (4059 342);
PAINT GREEN (4059 342);
FORCEPROP 2 LAST $SEC 1
J 2
(4000 400);
DISPLAY 0.680851 (4000 400);
PAINT MONO (4000 400);
DISPLAY INVISIBLE (4000 400);
FORCEPROP 2 LAST CDS_SEC 1
J 2
(4000 400);
DISPLAY 0.680851 (4000 400);
DISPLAY INVISIBLE (4000 400);
FORCEPROP 2 LASTPIN (3900 325) $PN 1
J 0
(3910 335);
DISPLAY 0.808511 (3910 335);
FORCEPROP 2 LASTPIN (3750 325) $PN 2
J 2
(3740 335);
DISPLAY 0.808511 (3740 335);
FORCEPROP 2 LAST VALUE DIFF BUS_0.22UF
J 2
(3675 325);
DISPLAY 0.553191 (3675 325);
FORCEPROP 1 LAST PIN_NAMES_ROTATE TRUE
J 2
(3825 325);
DISPLAY 0.489362 (3825 325);
PAINT GREEN (3825 325);
DISPLAY INVISIBLE (3825 325);
FORCEPROP 2 LAST CDS_LIB pure_quanta
J 2
(3825 325);
DISPLAY INVISIBLE (3825 325);
FORCEPROP 1 LAST CDS_LMAN_SYM_OUTLINE -25,50,25,-50
J 2
(3825 325);
DISPLAY 0.468085 (3825 325);
PAINT GREEN (3825 325);
DISPLAY INVISIBLE (3825 325);
FORCEPROP 2 LAST VOLTAGE 6.3V
J 2
(3475 375);
DISPLAY 0.553191 (3475 375);
DISPLAY INVISIBLE (3475 375);
FORCEPROP 1 LAST MATERIAL X6S
J 2
(3834 404);
DISPLAY 0.574468 (3834 404);
PAINT GREEN (3834 404);
DISPLAY INVISIBLE (3834 404);
FORCEPROP 2 LAST PACK_TYPE C0201
J 2
(3650 375);
DISPLAY 0.553191 (3650 375);
DISPLAY INVISIBLE (3650 375);
FORCEPROP 2 LAST TOLERANCE 20%
J 2
(3750 375);
DISPLAY 0.553191 (3750 375);
DISPLAY INVISIBLE (3750 375);
FORCEPROP 1 LAST PART_NUMBER SP_CH4221MEE01
J 2
(3709 413);
DISPLAY 0.574468 (3709 413);
PAINT GREEN (3709 413);
DISPLAY INVISIBLE (3709 413);
FORCEPROP 1 LAST LOCATION C899
J 0
(4075 400);
DISPLAY 1.021277 (4075 400);
DISPLAY INVISIBLE (4075 400);
FORCEPROP 1 LAST PATH I122
J 2
(3825 325);
DISPLAY 0.723404 (3825 325);
DISPLAY INVISIBLE (3825 325);
FORCEADD Q_CAP_DIFFBUS..2
R 2
(3825 525);
FORCEPROP 1 LAST LOCATION C897
J 2
(4059 542);
DISPLAY 0.723404 (4059 542);
PAINT GREEN (4059 542);
FORCEPROP 2 LAST $SEC 1
J 2
(4000 600);
DISPLAY 0.680851 (4000 600);
PAINT MONO (4000 600);
DISPLAY INVISIBLE (4000 600);
FORCEPROP 2 LAST CDS_SEC 1
J 2
(4000 600);
DISPLAY 0.680851 (4000 600);
DISPLAY INVISIBLE (4000 600);
FORCEPROP 2 LASTPIN (3900 525) $PN 1
J 0
(3910 535);
DISPLAY 0.808511 (3910 535);
FORCEPROP 2 LASTPIN (3750 525) $PN 2
J 2
(3740 535);
DISPLAY 0.808511 (3740 535);
FORCEPROP 2 LAST VALUE DIFF BUS_0.22UF
J 2
(3675 525);
DISPLAY 0.553191 (3675 525);
FORCEPROP 1 LAST PIN_NAMES_ROTATE TRUE
J 2
(3825 525);
DISPLAY 0.489362 (3825 525);
PAINT GREEN (3825 525);
DISPLAY INVISIBLE (3825 525);
FORCEPROP 2 LAST CDS_LIB pure_quanta
J 2
(3825 525);
DISPLAY INVISIBLE (3825 525);
FORCEPROP 1 LAST CDS_LMAN_SYM_OUTLINE -25,50,25,-50
J 2
(3825 525);
DISPLAY 0.468085 (3825 525);
PAINT GREEN (3825 525);
DISPLAY INVISIBLE (3825 525);
FORCEPROP 2 LAST VOLTAGE 6.3V
J 2
(3475 575);
DISPLAY 0.553191 (3475 575);
DISPLAY INVISIBLE (3475 575);
FORCEPROP 1 LAST MATERIAL X6S
J 2
(3834 604);
DISPLAY 0.574468 (3834 604);
PAINT GREEN (3834 604);
DISPLAY INVISIBLE (3834 604);
FORCEPROP 2 LAST PACK_TYPE C0201
J 2
(3650 575);
DISPLAY 0.553191 (3650 575);
DISPLAY INVISIBLE (3650 575);
FORCEPROP 2 LAST TOLERANCE 20%
J 2
(3750 575);
DISPLAY 0.553191 (3750 575);
DISPLAY INVISIBLE (3750 575);
FORCEPROP 1 LAST PART_NUMBER SP_CH4221MEE01
J 2
(3709 613);
DISPLAY 0.574468 (3709 613);
PAINT GREEN (3709 613);
DISPLAY INVISIBLE (3709 613);
FORCEPROP 1 LAST LOCATION C897
J 0
(4075 600);
DISPLAY 1.021277 (4075 600);
DISPLAY INVISIBLE (4075 600);
FORCEPROP 1 LAST PATH I123
J 2
(3825 525);
DISPLAY 0.723404 (3825 525);
DISPLAY INVISIBLE (3825 525);
FORCEADD Q_CAP_DIFFBUS..2
R 2
(3825 575);
FORCEPROP 1 LAST LOCATION C896
J 2
(4059 592);
DISPLAY 0.723404 (4059 592);
PAINT GREEN (4059 592);
FORCEPROP 2 LAST $SEC 1
J 2
(4000 650);
DISPLAY 0.680851 (4000 650);
PAINT MONO (4000 650);
DISPLAY INVISIBLE (4000 650);
FORCEPROP 2 LAST CDS_SEC 1
J 2
(4000 650);
DISPLAY 0.680851 (4000 650);
DISPLAY INVISIBLE (4000 650);
FORCEPROP 2 LASTPIN (3900 575) $PN 1
J 0
(3910 585);
DISPLAY 0.808511 (3910 585);
FORCEPROP 2 LASTPIN (3750 575) $PN 2
J 2
(3740 585);
DISPLAY 0.808511 (3740 585);
FORCEPROP 2 LAST VALUE DIFF BUS_0.22UF
J 2
(3675 575);
DISPLAY 0.553191 (3675 575);
FORCEPROP 1 LAST PIN_NAMES_ROTATE TRUE
J 2
(3825 575);
DISPLAY 0.489362 (3825 575);
PAINT GREEN (3825 575);
DISPLAY INVISIBLE (3825 575);
FORCEPROP 2 LAST CDS_LIB pure_quanta
J 2
(3825 575);
DISPLAY INVISIBLE (3825 575);
FORCEPROP 1 LAST CDS_LMAN_SYM_OUTLINE -25,50,25,-50
J 2
(3825 575);
DISPLAY 0.468085 (3825 575);
PAINT GREEN (3825 575);
DISPLAY INVISIBLE (3825 575);
FORCEPROP 2 LAST VOLTAGE 6.3V
J 2
(3475 625);
DISPLAY 0.553191 (3475 625);
DISPLAY INVISIBLE (3475 625);
FORCEPROP 1 LAST MATERIAL X6S
J 2
(3834 654);
DISPLAY 0.574468 (3834 654);
PAINT GREEN (3834 654);
DISPLAY INVISIBLE (3834 654);
FORCEPROP 2 LAST PACK_TYPE C0201
J 2
(3650 625);
DISPLAY 0.553191 (3650 625);
DISPLAY INVISIBLE (3650 625);
FORCEPROP 2 LAST TOLERANCE 20%
J 2
(3750 625);
DISPLAY 0.553191 (3750 625);
DISPLAY INVISIBLE (3750 625);
FORCEPROP 1 LAST PART_NUMBER SP_CH4221MEE01
J 2
(3709 663);
DISPLAY 0.574468 (3709 663);
PAINT GREEN (3709 663);
DISPLAY INVISIBLE (3709 663);
FORCEPROP 1 LAST LOCATION C896
J 0
(4075 650);
DISPLAY 1.021277 (4075 650);
DISPLAY INVISIBLE (4075 650);
FORCEPROP 1 LAST PATH I124
J 2
(3825 575);
DISPLAY 0.723404 (3825 575);
DISPLAY INVISIBLE (3825 575);
FORCEADD Q_CAP_DIFFBUS..2
R 2
(3825 725);
FORCEPROP 1 LAST LOCATION C895
J 2
(4059 742);
DISPLAY 0.723404 (4059 742);
PAINT GREEN (4059 742);
FORCEPROP 2 LAST $SEC 1
J 2
(4000 800);
DISPLAY 0.680851 (4000 800);
PAINT MONO (4000 800);
DISPLAY INVISIBLE (4000 800);
FORCEPROP 2 LAST CDS_SEC 1
J 2
(4000 800);
DISPLAY 0.680851 (4000 800);
DISPLAY INVISIBLE (4000 800);
FORCEPROP 2 LASTPIN (3900 725) $PN 1
J 0
(3910 735);
DISPLAY 0.808511 (3910 735);
FORCEPROP 2 LASTPIN (3750 725) $PN 2
J 2
(3740 735);
DISPLAY 0.808511 (3740 735);
FORCEPROP 2 LAST VALUE DIFF BUS_0.22UF
J 2
(3675 725);
DISPLAY 0.553191 (3675 725);
FORCEPROP 1 LAST PIN_NAMES_ROTATE TRUE
J 2
(3825 725);
DISPLAY 0.489362 (3825 725);
PAINT GREEN (3825 725);
DISPLAY INVISIBLE (3825 725);
FORCEPROP 1 LAST CDS_LMAN_SYM_OUTLINE -25,50,25,-50
J 2
(3825 725);
DISPLAY 0.468085 (3825 725);
PAINT GREEN (3825 725);
DISPLAY INVISIBLE (3825 725);
FORCEPROP 2 LAST CDS_LIB pure_quanta
J 2
(3825 725);
DISPLAY INVISIBLE (3825 725);
FORCEPROP 2 LAST VOLTAGE 6.3V
J 2
(3475 775);
DISPLAY 0.553191 (3475 775);
DISPLAY INVISIBLE (3475 775);
FORCEPROP 1 LAST MATERIAL X6S
J 2
(3834 804);
DISPLAY 0.574468 (3834 804);
PAINT GREEN (3834 804);
DISPLAY INVISIBLE (3834 804);
FORCEPROP 2 LAST PACK_TYPE C0201
J 2
(3650 775);
DISPLAY 0.553191 (3650 775);
DISPLAY INVISIBLE (3650 775);
FORCEPROP 2 LAST TOLERANCE 20%
J 2
(3750 775);
DISPLAY 0.553191 (3750 775);
DISPLAY INVISIBLE (3750 775);
FORCEPROP 1 LAST PART_NUMBER SP_CH4221MEE01
J 2
(3709 813);
DISPLAY 0.574468 (3709 813);
PAINT GREEN (3709 813);
DISPLAY INVISIBLE (3709 813);
FORCEPROP 1 LAST LOCATION C895
J 0
(4075 800);
DISPLAY 1.021277 (4075 800);
DISPLAY INVISIBLE (4075 800);
FORCEPROP 1 LAST PATH I125
J 2
(3825 725);
DISPLAY 0.723404 (3825 725);
DISPLAY INVISIBLE (3825 725);
FORCEADD Q_CAP_DIFFBUS..2
R 2
(3825 775);
FORCEPROP 1 LAST LOCATION C894
J 2
(4059 792);
DISPLAY 0.723404 (4059 792);
PAINT GREEN (4059 792);
FORCEPROP 2 LAST $SEC 1
J 2
(4000 850);
DISPLAY 0.680851 (4000 850);
PAINT MONO (4000 850);
DISPLAY INVISIBLE (4000 850);
FORCEPROP 2 LAST CDS_SEC 1
J 2
(4000 850);
DISPLAY 0.680851 (4000 850);
DISPLAY INVISIBLE (4000 850);
FORCEPROP 2 LASTPIN (3900 775) $PN 1
J 0
(3910 785);
DISPLAY 0.808511 (3910 785);
FORCEPROP 2 LASTPIN (3750 775) $PN 2
J 2
(3740 785);
DISPLAY 0.808511 (3740 785);
FORCEPROP 2 LAST VALUE DIFF BUS_0.22UF
J 2
(3675 775);
DISPLAY 0.553191 (3675 775);
FORCEPROP 1 LAST PIN_NAMES_ROTATE TRUE
J 2
(3825 775);
DISPLAY 0.489362 (3825 775);
PAINT GREEN (3825 775);
DISPLAY INVISIBLE (3825 775);
FORCEPROP 1 LAST CDS_LMAN_SYM_OUTLINE -25,50,25,-50
J 2
(3825 775);
DISPLAY 0.468085 (3825 775);
PAINT GREEN (3825 775);
DISPLAY INVISIBLE (3825 775);
FORCEPROP 2 LAST CDS_LIB pure_quanta
J 2
(3825 775);
DISPLAY INVISIBLE (3825 775);
FORCEPROP 2 LAST VOLTAGE 6.3V
J 2
(3475 825);
DISPLAY 0.553191 (3475 825);
DISPLAY INVISIBLE (3475 825);
FORCEPROP 1 LAST MATERIAL X6S
J 2
(3834 854);
DISPLAY 0.574468 (3834 854);
PAINT GREEN (3834 854);
DISPLAY INVISIBLE (3834 854);
FORCEPROP 2 LAST PACK_TYPE C0201
J 2
(3650 825);
DISPLAY 0.553191 (3650 825);
DISPLAY INVISIBLE (3650 825);
FORCEPROP 2 LAST TOLERANCE 20%
J 2
(3750 825);
DISPLAY 0.553191 (3750 825);
DISPLAY INVISIBLE (3750 825);
FORCEPROP 1 LAST PART_NUMBER SP_CH4221MEE01
J 2
(3709 863);
DISPLAY 0.574468 (3709 863);
PAINT GREEN (3709 863);
DISPLAY INVISIBLE (3709 863);
FORCEPROP 1 LAST LOCATION C894
J 0
(4075 850);
DISPLAY 1.021277 (4075 850);
DISPLAY INVISIBLE (4075 850);
FORCEPROP 1 LAST PATH I126
J 2
(3825 775);
DISPLAY 0.723404 (3825 775);
DISPLAY INVISIBLE (3825 775);
FORCEADD Q_CAP_DIFFBUS..2
R 2
(3825 975);
FORCEPROP 1 LAST LOCATION C892
J 2
(4059 992);
DISPLAY 0.723404 (4059 992);
PAINT GREEN (4059 992);
FORCEPROP 2 LAST $SEC 1
J 2
(4000 1050);
DISPLAY 0.680851 (4000 1050);
PAINT MONO (4000 1050);
DISPLAY INVISIBLE (4000 1050);
FORCEPROP 2 LAST CDS_SEC 1
J 2
(4000 1050);
DISPLAY 0.680851 (4000 1050);
DISPLAY INVISIBLE (4000 1050);
FORCEPROP 2 LASTPIN (3900 975) $PN 1
J 0
(3910 985);
DISPLAY 0.808511 (3910 985);
FORCEPROP 2 LASTPIN (3750 975) $PN 2
J 2
(3740 985);
DISPLAY 0.808511 (3740 985);
FORCEPROP 2 LAST VALUE DIFF BUS_0.22UF
J 2
(3675 975);
DISPLAY 0.553191 (3675 975);
FORCEPROP 1 LAST PIN_NAMES_ROTATE TRUE
J 2
(3825 975);
DISPLAY 0.489362 (3825 975);
PAINT GREEN (3825 975);
DISPLAY INVISIBLE (3825 975);
FORCEPROP 2 LAST CDS_LIB pure_quanta
J 2
(3825 975);
DISPLAY INVISIBLE (3825 975);
FORCEPROP 1 LAST CDS_LMAN_SYM_OUTLINE -25,50,25,-50
J 2
(3825 975);
DISPLAY 0.468085 (3825 975);
PAINT GREEN (3825 975);
DISPLAY INVISIBLE (3825 975);
FORCEPROP 2 LAST VOLTAGE 6.3V
J 2
(3475 1025);
DISPLAY 0.553191 (3475 1025);
DISPLAY INVISIBLE (3475 1025);
FORCEPROP 1 LAST MATERIAL X6S
J 2
(3834 1054);
DISPLAY 0.574468 (3834 1054);
PAINT GREEN (3834 1054);
DISPLAY INVISIBLE (3834 1054);
FORCEPROP 2 LAST PACK_TYPE C0201
J 2
(3650 1025);
DISPLAY 0.553191 (3650 1025);
DISPLAY INVISIBLE (3650 1025);
FORCEPROP 2 LAST TOLERANCE 20%
J 2
(3750 1025);
DISPLAY 0.553191 (3750 1025);
DISPLAY INVISIBLE (3750 1025);
FORCEPROP 1 LAST PART_NUMBER SP_CH4221MEE01
J 2
(3709 1063);
DISPLAY 0.574468 (3709 1063);
PAINT GREEN (3709 1063);
DISPLAY INVISIBLE (3709 1063);
FORCEPROP 1 LAST LOCATION C892
J 0
(4075 1050);
DISPLAY 1.021277 (4075 1050);
DISPLAY INVISIBLE (4075 1050);
FORCEPROP 1 LAST PATH I127
J 2
(3825 975);
DISPLAY 0.723404 (3825 975);
DISPLAY INVISIBLE (3825 975);
FORCEADD Q_CAP_DIFFBUS..2
R 2
(3825 925);
FORCEPROP 1 LAST LOCATION C893
J 2
(4059 942);
DISPLAY 0.723404 (4059 942);
PAINT GREEN (4059 942);
FORCEPROP 2 LAST $SEC 1
J 2
(4000 1000);
DISPLAY 0.680851 (4000 1000);
PAINT MONO (4000 1000);
DISPLAY INVISIBLE (4000 1000);
FORCEPROP 2 LAST CDS_SEC 1
J 2
(4000 1000);
DISPLAY 0.680851 (4000 1000);
DISPLAY INVISIBLE (4000 1000);
FORCEPROP 2 LASTPIN (3900 925) $PN 1
J 0
(3910 935);
DISPLAY 0.808511 (3910 935);
FORCEPROP 2 LASTPIN (3750 925) $PN 2
J 2
(3740 935);
DISPLAY 0.808511 (3740 935);
FORCEPROP 2 LAST VALUE DIFF BUS_0.22UF
J 2
(3675 925);
DISPLAY 0.553191 (3675 925);
FORCEPROP 1 LAST PIN_NAMES_ROTATE TRUE
J 2
(3825 925);
DISPLAY 0.489362 (3825 925);
PAINT GREEN (3825 925);
DISPLAY INVISIBLE (3825 925);
FORCEPROP 2 LAST CDS_LIB pure_quanta
J 2
(3825 925);
DISPLAY INVISIBLE (3825 925);
FORCEPROP 1 LAST CDS_LMAN_SYM_OUTLINE -25,50,25,-50
J 2
(3825 925);
DISPLAY 0.468085 (3825 925);
PAINT GREEN (3825 925);
DISPLAY INVISIBLE (3825 925);
FORCEPROP 2 LAST VOLTAGE 6.3V
J 2
(3475 975);
DISPLAY 0.553191 (3475 975);
DISPLAY INVISIBLE (3475 975);
FORCEPROP 1 LAST MATERIAL X6S
J 2
(3834 1004);
DISPLAY 0.574468 (3834 1004);
PAINT GREEN (3834 1004);
DISPLAY INVISIBLE (3834 1004);
FORCEPROP 2 LAST PACK_TYPE C0201
J 2
(3650 975);
DISPLAY 0.553191 (3650 975);
DISPLAY INVISIBLE (3650 975);
FORCEPROP 2 LAST TOLERANCE 20%
J 2
(3750 975);
DISPLAY 0.553191 (3750 975);
DISPLAY INVISIBLE (3750 975);
FORCEPROP 1 LAST PART_NUMBER SP_CH4221MEE01
J 2
(3709 1013);
DISPLAY 0.574468 (3709 1013);
PAINT GREEN (3709 1013);
DISPLAY INVISIBLE (3709 1013);
FORCEPROP 1 LAST LOCATION C893
J 0
(4075 1000);
DISPLAY 1.021277 (4075 1000);
DISPLAY INVISIBLE (4075 1000);
FORCEPROP 1 LAST PATH I128
J 2
(3825 925);
DISPLAY 0.723404 (3825 925);
DISPLAY INVISIBLE (3825 925);
FORCEADD TAP..1
R 2
(3100 1175);
FORCEPROP 3 LASTPIN (3150 1175) SIG_NAME P5E_CPU0_P3_TX_DN<5>
J 0
(3160 1185);
DISPLAY 0.659574 (3160 1185);
PAINT MONO (3160 1185);
DISPLAY INVISIBLE (3160 1185);
FORCEPROP 1 LASTPIN (3150 1175) BN 5
J 2
(3162 1183);
DISPLAY 0.680851 (3162 1183);
PAINT GREEN (3162 1183);
FORCEPROP 2 LAST CDS_LIB standard
J 0
(3100 1175);
DISPLAY INVISIBLE (3100 1175);
FORCEPROP 1 LAST BODY_TYPE PLUMBING
J 2
(3100 1225);
DISPLAY 0.872340 (3100 1225);
PAINT GREEN (3100 1225);
DISPLAY INVISIBLE (3100 1225);
FORCEPROP 1 LAST HDL_TAP TRUE
J 2
(2775 1050);
DISPLAY 0.872340 (2775 1050);
DISPLAY INVISIBLE (2775 1050);
FORCEPROP 1 LAST PATH I129
J 2
(3102 1175);
DISPLAY 0.872340 (3102 1175);
PAINT GREEN (3102 1175);
DISPLAY INVISIBLE (3102 1175);
FORCEADD TAP..1
R 2
(-1375 775);
FORCEPROP 3 LASTPIN (-1325 775) SIG_NAME P5E_CPU0_P2_TX_DN<3>
J 0
(-1315 785);
DISPLAY 0.659574 (-1315 785);
PAINT MONO (-1315 785);
DISPLAY INVISIBLE (-1315 785);
FORCEPROP 1 LASTPIN (-1325 775) BN 3
J 2
(-1313 783);
DISPLAY 0.680851 (-1313 783);
PAINT GREEN (-1313 783);
FORCEPROP 2 LAST CDS_LIB standard
J 0
(-1375 775);
DISPLAY INVISIBLE (-1375 775);
FORCEPROP 1 LAST BODY_TYPE PLUMBING
J 2
(-1375 825);
DISPLAY 0.872340 (-1375 825);
PAINT GREEN (-1375 825);
DISPLAY INVISIBLE (-1375 825);
FORCEPROP 1 LAST HDL_TAP TRUE
J 2
(-1700 650);
DISPLAY 0.872340 (-1700 650);
DISPLAY INVISIBLE (-1700 650);
FORCEPROP 1 LAST PATH I13
J 2
(-1373 775);
DISPLAY 0.872340 (-1373 775);
PAINT GREEN (-1373 775);
DISPLAY INVISIBLE (-1373 775);
FORCEADD TAP..1
R 2
(3100 1375);
FORCEPROP 3 LASTPIN (3150 1375) SIG_NAME P5E_CPU0_P3_TX_DN<6>
J 0
(3160 1385);
DISPLAY 0.659574 (3160 1385);
PAINT MONO (3160 1385);
DISPLAY INVISIBLE (3160 1385);
FORCEPROP 1 LASTPIN (3150 1375) BN 6
J 2
(3162 1383);
DISPLAY 0.680851 (3162 1383);
PAINT GREEN (3162 1383);
FORCEPROP 2 LAST CDS_LIB standard
J 0
(3100 1375);
DISPLAY INVISIBLE (3100 1375);
FORCEPROP 1 LAST BODY_TYPE PLUMBING
J 2
(3100 1425);
DISPLAY 0.872340 (3100 1425);
PAINT GREEN (3100 1425);
DISPLAY INVISIBLE (3100 1425);
FORCEPROP 1 LAST HDL_TAP TRUE
J 2
(2775 1250);
DISPLAY 0.872340 (2775 1250);
DISPLAY INVISIBLE (2775 1250);
FORCEPROP 1 LAST PATH I130
J 2
(3102 1375);
DISPLAY 0.872340 (3102 1375);
PAINT GREEN (3102 1375);
DISPLAY INVISIBLE (3102 1375);
FORCEADD TAP..1
R 2
(3100 1575);
FORCEPROP 3 LASTPIN (3150 1575) SIG_NAME P5E_CPU0_P3_TX_DN<7>
J 0
(3160 1585);
DISPLAY 0.659574 (3160 1585);
PAINT MONO (3160 1585);
DISPLAY INVISIBLE (3160 1585);
FORCEPROP 1 LASTPIN (3150 1575) BN 7
J 2
(3162 1583);
DISPLAY 0.680851 (3162 1583);
PAINT GREEN (3162 1583);
FORCEPROP 2 LAST CDS_LIB standard
J 0
(3100 1575);
DISPLAY INVISIBLE (3100 1575);
FORCEPROP 1 LAST BODY_TYPE PLUMBING
J 2
(3100 1625);
DISPLAY 0.872340 (3100 1625);
PAINT GREEN (3100 1625);
DISPLAY INVISIBLE (3100 1625);
FORCEPROP 1 LAST HDL_TAP TRUE
J 2
(2775 1450);
DISPLAY 0.872340 (2775 1450);
DISPLAY INVISIBLE (2775 1450);
FORCEPROP 1 LAST PATH I131
J 2
(3102 1575);
DISPLAY 0.872340 (3102 1575);
PAINT GREEN (3102 1575);
DISPLAY INVISIBLE (3102 1575);
FORCEADD Q_CAP_DIFFBUS..2
R 2
(3825 1125);
FORCEPROP 1 LAST LOCATION C891
J 2
(4059 1142);
DISPLAY 0.723404 (4059 1142);
PAINT GREEN (4059 1142);
FORCEPROP 2 LAST $SEC 1
J 2
(4000 1200);
DISPLAY 0.680851 (4000 1200);
PAINT MONO (4000 1200);
DISPLAY INVISIBLE (4000 1200);
FORCEPROP 2 LAST CDS_SEC 1
J 2
(4000 1200);
DISPLAY 0.680851 (4000 1200);
DISPLAY INVISIBLE (4000 1200);
FORCEPROP 2 LASTPIN (3900 1125) $PN 1
J 0
(3910 1135);
DISPLAY 0.808511 (3910 1135);
FORCEPROP 2 LASTPIN (3750 1125) $PN 2
J 2
(3740 1135);
DISPLAY 0.808511 (3740 1135);
FORCEPROP 2 LAST VALUE DIFF BUS_0.22UF
J 2
(3675 1125);
DISPLAY 0.553191 (3675 1125);
FORCEPROP 1 LAST PIN_NAMES_ROTATE TRUE
J 2
(3825 1125);
DISPLAY 0.489362 (3825 1125);
PAINT GREEN (3825 1125);
DISPLAY INVISIBLE (3825 1125);
FORCEPROP 2 LAST CDS_LIB pure_quanta
J 2
(3825 1125);
DISPLAY INVISIBLE (3825 1125);
FORCEPROP 1 LAST CDS_LMAN_SYM_OUTLINE -25,50,25,-50
J 2
(3825 1125);
DISPLAY 0.468085 (3825 1125);
PAINT GREEN (3825 1125);
DISPLAY INVISIBLE (3825 1125);
FORCEPROP 2 LAST VOLTAGE 6.3V
J 2
(3475 1175);
DISPLAY 0.553191 (3475 1175);
DISPLAY INVISIBLE (3475 1175);
FORCEPROP 1 LAST MATERIAL X6S
J 2
(3834 1204);
DISPLAY 0.574468 (3834 1204);
PAINT GREEN (3834 1204);
DISPLAY INVISIBLE (3834 1204);
FORCEPROP 2 LAST PACK_TYPE C0201
J 2
(3650 1175);
DISPLAY 0.553191 (3650 1175);
DISPLAY INVISIBLE (3650 1175);
FORCEPROP 2 LAST TOLERANCE 20%
J 2
(3750 1175);
DISPLAY 0.553191 (3750 1175);
DISPLAY INVISIBLE (3750 1175);
FORCEPROP 1 LAST PART_NUMBER SP_CH4221MEE01
J 2
(3709 1213);
DISPLAY 0.574468 (3709 1213);
PAINT GREEN (3709 1213);
DISPLAY INVISIBLE (3709 1213);
FORCEPROP 1 LAST LOCATION C891
J 0
(4075 1200);
DISPLAY 1.021277 (4075 1200);
DISPLAY INVISIBLE (4075 1200);
FORCEPROP 1 LAST PATH I132
J 2
(3825 1125);
DISPLAY 0.723404 (3825 1125);
DISPLAY INVISIBLE (3825 1125);
FORCEADD Q_CAP_DIFFBUS..2
R 2
(3825 1175);
FORCEPROP 1 LAST LOCATION C890
J 2
(4059 1192);
DISPLAY 0.723404 (4059 1192);
PAINT GREEN (4059 1192);
FORCEPROP 2 LAST $SEC 1
J 2
(4000 1250);
DISPLAY 0.680851 (4000 1250);
PAINT MONO (4000 1250);
DISPLAY INVISIBLE (4000 1250);
FORCEPROP 2 LAST CDS_SEC 1
J 2
(4000 1250);
DISPLAY 0.680851 (4000 1250);
DISPLAY INVISIBLE (4000 1250);
FORCEPROP 2 LASTPIN (3900 1175) $PN 1
J 0
(3910 1185);
DISPLAY 0.808511 (3910 1185);
FORCEPROP 2 LASTPIN (3750 1175) $PN 2
J 2
(3740 1185);
DISPLAY 0.808511 (3740 1185);
FORCEPROP 2 LAST VALUE DIFF BUS_0.22UF
J 2
(3675 1175);
DISPLAY 0.553191 (3675 1175);
FORCEPROP 1 LAST PIN_NAMES_ROTATE TRUE
J 2
(3825 1175);
DISPLAY 0.489362 (3825 1175);
PAINT GREEN (3825 1175);
DISPLAY INVISIBLE (3825 1175);
FORCEPROP 2 LAST CDS_LIB pure_quanta
J 2
(3825 1175);
DISPLAY INVISIBLE (3825 1175);
FORCEPROP 1 LAST CDS_LMAN_SYM_OUTLINE -25,50,25,-50
J 2
(3825 1175);
DISPLAY 0.468085 (3825 1175);
PAINT GREEN (3825 1175);
DISPLAY INVISIBLE (3825 1175);
FORCEPROP 2 LAST VOLTAGE 6.3V
J 2
(3475 1225);
DISPLAY 0.553191 (3475 1225);
DISPLAY INVISIBLE (3475 1225);
FORCEPROP 1 LAST MATERIAL X6S
J 2
(3834 1254);
DISPLAY 0.574468 (3834 1254);
PAINT GREEN (3834 1254);
DISPLAY INVISIBLE (3834 1254);
FORCEPROP 2 LAST PACK_TYPE C0201
J 2
(3650 1225);
DISPLAY 0.553191 (3650 1225);
DISPLAY INVISIBLE (3650 1225);
FORCEPROP 2 LAST TOLERANCE 20%
J 2
(3750 1225);
DISPLAY 0.553191 (3750 1225);
DISPLAY INVISIBLE (3750 1225);
FORCEPROP 1 LAST PART_NUMBER SP_CH4221MEE01
J 2
(3709 1263);
DISPLAY 0.574468 (3709 1263);
PAINT GREEN (3709 1263);
DISPLAY INVISIBLE (3709 1263);
FORCEPROP 1 LAST LOCATION C890
J 0
(4075 1250);
DISPLAY 1.021277 (4075 1250);
DISPLAY INVISIBLE (4075 1250);
FORCEPROP 1 LAST PATH I133
J 2
(3825 1175);
DISPLAY 0.723404 (3825 1175);
DISPLAY INVISIBLE (3825 1175);
FORCEADD Q_CAP_DIFFBUS..2
R 2
(3825 1325);
FORCEPROP 1 LAST LOCATION C889
J 2
(4059 1342);
DISPLAY 0.723404 (4059 1342);
PAINT GREEN (4059 1342);
FORCEPROP 2 LAST $SEC 1
J 2
(4000 1400);
DISPLAY 0.680851 (4000 1400);
PAINT MONO (4000 1400);
DISPLAY INVISIBLE (4000 1400);
FORCEPROP 2 LAST CDS_SEC 1
J 2
(4000 1400);
DISPLAY 0.680851 (4000 1400);
DISPLAY INVISIBLE (4000 1400);
FORCEPROP 2 LASTPIN (3900 1325) $PN 1
J 0
(3910 1335);
DISPLAY 0.808511 (3910 1335);
FORCEPROP 2 LASTPIN (3750 1325) $PN 2
J 2
(3740 1335);
DISPLAY 0.808511 (3740 1335);
FORCEPROP 2 LAST VALUE DIFF BUS_0.22UF
J 2
(3675 1325);
DISPLAY 0.553191 (3675 1325);
FORCEPROP 1 LAST PIN_NAMES_ROTATE TRUE
J 2
(3825 1325);
DISPLAY 0.489362 (3825 1325);
PAINT GREEN (3825 1325);
DISPLAY INVISIBLE (3825 1325);
FORCEPROP 2 LAST CDS_LIB pure_quanta
J 2
(3825 1325);
DISPLAY INVISIBLE (3825 1325);
FORCEPROP 1 LAST CDS_LMAN_SYM_OUTLINE -25,50,25,-50
J 2
(3825 1325);
DISPLAY 0.468085 (3825 1325);
PAINT GREEN (3825 1325);
DISPLAY INVISIBLE (3825 1325);
FORCEPROP 2 LAST VOLTAGE 6.3V
J 2
(3475 1375);
DISPLAY 0.553191 (3475 1375);
DISPLAY INVISIBLE (3475 1375);
FORCEPROP 1 LAST MATERIAL X6S
J 2
(3834 1404);
DISPLAY 0.574468 (3834 1404);
PAINT GREEN (3834 1404);
DISPLAY INVISIBLE (3834 1404);
FORCEPROP 2 LAST PACK_TYPE C0201
J 2
(3650 1375);
DISPLAY 0.553191 (3650 1375);
DISPLAY INVISIBLE (3650 1375);
FORCEPROP 2 LAST TOLERANCE 20%
J 2
(3750 1375);
DISPLAY 0.553191 (3750 1375);
DISPLAY INVISIBLE (3750 1375);
FORCEPROP 1 LAST PART_NUMBER SP_CH4221MEE01
J 2
(3709 1413);
DISPLAY 0.574468 (3709 1413);
PAINT GREEN (3709 1413);
DISPLAY INVISIBLE (3709 1413);
FORCEPROP 1 LAST LOCATION C889
J 0
(4075 1400);
DISPLAY 1.021277 (4075 1400);
DISPLAY INVISIBLE (4075 1400);
FORCEPROP 1 LAST PATH I134
J 2
(3825 1325);
DISPLAY 0.723404 (3825 1325);
DISPLAY INVISIBLE (3825 1325);
FORCEADD Q_CAP_DIFFBUS..2
R 2
(3825 1375);
FORCEPROP 1 LAST LOCATION C888
J 2
(4059 1392);
DISPLAY 0.723404 (4059 1392);
PAINT GREEN (4059 1392);
FORCEPROP 2 LAST $SEC 1
J 2
(4000 1450);
DISPLAY 0.680851 (4000 1450);
PAINT MONO (4000 1450);
DISPLAY INVISIBLE (4000 1450);
FORCEPROP 2 LAST CDS_SEC 1
J 2
(4000 1450);
DISPLAY 0.680851 (4000 1450);
DISPLAY INVISIBLE (4000 1450);
FORCEPROP 2 LASTPIN (3900 1375) $PN 1
J 0
(3910 1385);
DISPLAY 0.808511 (3910 1385);
FORCEPROP 2 LASTPIN (3750 1375) $PN 2
J 2
(3740 1385);
DISPLAY 0.808511 (3740 1385);
FORCEPROP 2 LAST VALUE DIFF BUS_0.22UF
J 2
(3675 1375);
DISPLAY 0.553191 (3675 1375);
FORCEPROP 1 LAST PIN_NAMES_ROTATE TRUE
J 2
(3825 1375);
DISPLAY 0.489362 (3825 1375);
PAINT GREEN (3825 1375);
DISPLAY INVISIBLE (3825 1375);
FORCEPROP 2 LAST CDS_LIB pure_quanta
J 2
(3825 1375);
DISPLAY INVISIBLE (3825 1375);
FORCEPROP 1 LAST CDS_LMAN_SYM_OUTLINE -25,50,25,-50
J 2
(3825 1375);
DISPLAY 0.468085 (3825 1375);
PAINT GREEN (3825 1375);
DISPLAY INVISIBLE (3825 1375);
FORCEPROP 2 LAST VOLTAGE 6.3V
J 2
(3475 1425);
DISPLAY 0.553191 (3475 1425);
DISPLAY INVISIBLE (3475 1425);
FORCEPROP 1 LAST MATERIAL X6S
J 2
(3834 1454);
DISPLAY 0.574468 (3834 1454);
PAINT GREEN (3834 1454);
DISPLAY INVISIBLE (3834 1454);
FORCEPROP 2 LAST PACK_TYPE C0201
J 2
(3650 1425);
DISPLAY 0.553191 (3650 1425);
DISPLAY INVISIBLE (3650 1425);
FORCEPROP 2 LAST TOLERANCE 20%
J 2
(3750 1425);
DISPLAY 0.553191 (3750 1425);
DISPLAY INVISIBLE (3750 1425);
FORCEPROP 1 LAST PART_NUMBER SP_CH4221MEE01
J 2
(3709 1463);
DISPLAY 0.574468 (3709 1463);
PAINT GREEN (3709 1463);
DISPLAY INVISIBLE (3709 1463);
FORCEPROP 1 LAST LOCATION C888
J 0
(4075 1450);
DISPLAY 1.021277 (4075 1450);
DISPLAY INVISIBLE (4075 1450);
FORCEPROP 1 LAST PATH I135
J 2
(3825 1375);
DISPLAY 0.723404 (3825 1375);
DISPLAY INVISIBLE (3825 1375);
FORCEADD Q_CAP_DIFFBUS..2
R 2
(3825 1525);
FORCEPROP 1 LAST LOCATION C887
J 2
(4059 1542);
DISPLAY 0.723404 (4059 1542);
PAINT GREEN (4059 1542);
FORCEPROP 2 LAST $SEC 1
J 2
(4000 1600);
DISPLAY 0.680851 (4000 1600);
PAINT MONO (4000 1600);
DISPLAY INVISIBLE (4000 1600);
FORCEPROP 2 LAST CDS_SEC 1
J 2
(4000 1600);
DISPLAY 0.680851 (4000 1600);
DISPLAY INVISIBLE (4000 1600);
FORCEPROP 2 LASTPIN (3900 1525) $PN 1
J 0
(3910 1535);
DISPLAY 0.808511 (3910 1535);
FORCEPROP 2 LASTPIN (3750 1525) $PN 2
J 2
(3740 1535);
DISPLAY 0.808511 (3740 1535);
FORCEPROP 2 LAST VALUE DIFF BUS_0.22UF
J 2
(3675 1525);
DISPLAY 0.553191 (3675 1525);
FORCEPROP 1 LAST PIN_NAMES_ROTATE TRUE
J 2
(3825 1525);
DISPLAY 0.489362 (3825 1525);
PAINT GREEN (3825 1525);
DISPLAY INVISIBLE (3825 1525);
FORCEPROP 2 LAST CDS_LIB pure_quanta
J 2
(3825 1525);
DISPLAY INVISIBLE (3825 1525);
FORCEPROP 1 LAST CDS_LMAN_SYM_OUTLINE -25,50,25,-50
J 2
(3825 1525);
DISPLAY 0.468085 (3825 1525);
PAINT GREEN (3825 1525);
DISPLAY INVISIBLE (3825 1525);
FORCEPROP 2 LAST VOLTAGE 6.3V
J 2
(3475 1575);
DISPLAY 0.553191 (3475 1575);
DISPLAY INVISIBLE (3475 1575);
FORCEPROP 1 LAST MATERIAL X6S
J 2
(3834 1604);
DISPLAY 0.574468 (3834 1604);
PAINT GREEN (3834 1604);
DISPLAY INVISIBLE (3834 1604);
FORCEPROP 2 LAST PACK_TYPE C0201
J 2
(3650 1575);
DISPLAY 0.553191 (3650 1575);
DISPLAY INVISIBLE (3650 1575);
FORCEPROP 2 LAST TOLERANCE 20%
J 2
(3750 1575);
DISPLAY 0.553191 (3750 1575);
DISPLAY INVISIBLE (3750 1575);
FORCEPROP 1 LAST PART_NUMBER SP_CH4221MEE01
J 2
(3709 1613);
DISPLAY 0.574468 (3709 1613);
PAINT GREEN (3709 1613);
DISPLAY INVISIBLE (3709 1613);
FORCEPROP 1 LAST LOCATION C887
J 0
(4075 1600);
DISPLAY 1.021277 (4075 1600);
DISPLAY INVISIBLE (4075 1600);
FORCEPROP 1 LAST PATH I136
J 2
(3825 1525);
DISPLAY 0.723404 (3825 1525);
DISPLAY INVISIBLE (3825 1525);
FORCEADD Q_CAP_DIFFBUS..2
R 2
(3825 1575);
FORCEPROP 1 LAST LOCATION C886
J 2
(4059 1592);
DISPLAY 0.723404 (4059 1592);
PAINT GREEN (4059 1592);
FORCEPROP 2 LAST $SEC 1
J 2
(4000 1650);
DISPLAY 0.680851 (4000 1650);
PAINT MONO (4000 1650);
DISPLAY INVISIBLE (4000 1650);
FORCEPROP 2 LAST CDS_SEC 1
J 2
(4000 1650);
DISPLAY 0.680851 (4000 1650);
DISPLAY INVISIBLE (4000 1650);
FORCEPROP 2 LASTPIN (3900 1575) $PN 1
J 0
(3910 1585);
DISPLAY 0.808511 (3910 1585);
FORCEPROP 2 LASTPIN (3750 1575) $PN 2
J 2
(3740 1585);
DISPLAY 0.808511 (3740 1585);
FORCEPROP 2 LAST VALUE DIFF BUS_0.22UF
J 2
(3675 1575);
DISPLAY 0.553191 (3675 1575);
FORCEPROP 1 LAST PIN_NAMES_ROTATE TRUE
J 2
(3825 1575);
DISPLAY 0.489362 (3825 1575);
PAINT GREEN (3825 1575);
DISPLAY INVISIBLE (3825 1575);
FORCEPROP 1 LAST CDS_LMAN_SYM_OUTLINE -25,50,25,-50
J 2
(3825 1575);
DISPLAY 0.468085 (3825 1575);
PAINT GREEN (3825 1575);
DISPLAY INVISIBLE (3825 1575);
FORCEPROP 2 LAST CDS_LIB pure_quanta
J 2
(3825 1575);
DISPLAY INVISIBLE (3825 1575);
FORCEPROP 2 LAST VOLTAGE 6.3V
J 2
(3475 1625);
DISPLAY 0.553191 (3475 1625);
DISPLAY INVISIBLE (3475 1625);
FORCEPROP 1 LAST MATERIAL X6S
J 2
(3834 1654);
DISPLAY 0.574468 (3834 1654);
PAINT GREEN (3834 1654);
DISPLAY INVISIBLE (3834 1654);
FORCEPROP 2 LAST PACK_TYPE C0201
J 2
(3650 1625);
DISPLAY 0.553191 (3650 1625);
DISPLAY INVISIBLE (3650 1625);
FORCEPROP 2 LAST TOLERANCE 20%
J 2
(3750 1625);
DISPLAY 0.553191 (3750 1625);
DISPLAY INVISIBLE (3750 1625);
FORCEPROP 1 LAST PART_NUMBER SP_CH4221MEE01
J 2
(3709 1663);
DISPLAY 0.574468 (3709 1663);
PAINT GREEN (3709 1663);
DISPLAY INVISIBLE (3709 1663);
FORCEPROP 1 LAST LOCATION C886
J 0
(4075 1650);
DISPLAY 1.021277 (4075 1650);
DISPLAY INVISIBLE (4075 1650);
FORCEPROP 1 LAST PATH I137
J 2
(3825 1575);
DISPLAY 0.723404 (3825 1575);
DISPLAY INVISIBLE (3825 1575);
FORCEADD TAP..1
R 2
(2850 2100);
FORCEPROP 3 LASTPIN (2900 2100) SIG_NAME P5E_CPU0_P3_TX_DP<8>
J 0
(2910 2110);
DISPLAY 0.659574 (2910 2110);
PAINT MONO (2910 2110);
DISPLAY INVISIBLE (2910 2110);
FORCEPROP 1 LASTPIN (2900 2100) BN 8
J 2
(2912 2108);
DISPLAY 0.680851 (2912 2108);
PAINT GREEN (2912 2108);
FORCEPROP 2 LAST CDS_LIB standard
J 0
(2850 2100);
DISPLAY INVISIBLE (2850 2100);
FORCEPROP 1 LAST BODY_TYPE PLUMBING
J 2
(2850 2150);
DISPLAY 0.872340 (2850 2150);
PAINT GREEN (2850 2150);
DISPLAY INVISIBLE (2850 2150);
FORCEPROP 1 LAST HDL_TAP TRUE
J 2
(2525 1975);
DISPLAY 0.872340 (2525 1975);
DISPLAY INVISIBLE (2525 1975);
FORCEPROP 1 LAST PATH I138
J 2
(2852 2100);
DISPLAY 0.872340 (2852 2100);
PAINT GREEN (2852 2100);
DISPLAY INVISIBLE (2852 2100);
FORCEADD TAP..1
R 2
(2850 2300);
FORCEPROP 3 LASTPIN (2900 2300) SIG_NAME P5E_CPU0_P3_TX_DP<9>
J 0
(2910 2310);
DISPLAY 0.659574 (2910 2310);
PAINT MONO (2910 2310);
DISPLAY INVISIBLE (2910 2310);
FORCEPROP 1 LASTPIN (2900 2300) BN 9
J 2
(2912 2308);
DISPLAY 0.680851 (2912 2308);
PAINT GREEN (2912 2308);
FORCEPROP 2 LAST CDS_LIB standard
J 0
(2850 2300);
DISPLAY INVISIBLE (2850 2300);
FORCEPROP 1 LAST BODY_TYPE PLUMBING
J 2
(2850 2350);
DISPLAY 0.872340 (2850 2350);
PAINT GREEN (2850 2350);
DISPLAY INVISIBLE (2850 2350);
FORCEPROP 1 LAST HDL_TAP TRUE
J 2
(2525 2175);
DISPLAY 0.872340 (2525 2175);
DISPLAY INVISIBLE (2525 2175);
FORCEPROP 1 LAST PATH I139
J 2
(2852 2300);
DISPLAY 0.872340 (2852 2300);
PAINT GREEN (2852 2300);
DISPLAY INVISIBLE (2852 2300);
FORCEADD TAP..1
R 2
(-1375 975);
FORCEPROP 3 LASTPIN (-1325 975) SIG_NAME P5E_CPU0_P2_TX_DN<4>
J 0
(-1315 985);
DISPLAY 0.659574 (-1315 985);
PAINT MONO (-1315 985);
DISPLAY INVISIBLE (-1315 985);
FORCEPROP 1 LASTPIN (-1325 975) BN 4
J 2
(-1313 983);
DISPLAY 0.680851 (-1313 983);
PAINT GREEN (-1313 983);
FORCEPROP 2 LAST CDS_LIB standard
J 0
(-1375 975);
DISPLAY INVISIBLE (-1375 975);
FORCEPROP 1 LAST BODY_TYPE PLUMBING
J 2
(-1375 1025);
DISPLAY 0.872340 (-1375 1025);
PAINT GREEN (-1375 1025);
DISPLAY INVISIBLE (-1375 1025);
FORCEPROP 1 LAST HDL_TAP TRUE
J 2
(-1700 850);
DISPLAY 0.872340 (-1700 850);
DISPLAY INVISIBLE (-1700 850);
FORCEPROP 1 LAST PATH I14
J 2
(-1373 975);
DISPLAY 0.872340 (-1373 975);
PAINT GREEN (-1373 975);
DISPLAY INVISIBLE (-1373 975);
FORCEADD TAP..1
R 2
(2850 2500);
FORCEPROP 3 LASTPIN (2900 2500) SIG_NAME P5E_CPU0_P3_TX_DP<10>
J 0
(2910 2510);
DISPLAY 0.659574 (2910 2510);
PAINT MONO (2910 2510);
DISPLAY INVISIBLE (2910 2510);
FORCEPROP 1 LASTPIN (2900 2500) BN 10
J 2
(2912 2508);
DISPLAY 0.680851 (2912 2508);
PAINT GREEN (2912 2508);
FORCEPROP 2 LAST CDS_LIB standard
J 0
(2850 2500);
DISPLAY INVISIBLE (2850 2500);
FORCEPROP 1 LAST BODY_TYPE PLUMBING
J 2
(2850 2550);
DISPLAY 0.872340 (2850 2550);
PAINT GREEN (2850 2550);
DISPLAY INVISIBLE (2850 2550);
FORCEPROP 1 LAST HDL_TAP TRUE
J 2
(2525 2375);
DISPLAY 0.872340 (2525 2375);
DISPLAY INVISIBLE (2525 2375);
FORCEPROP 1 LAST PATH I140
J 2
(2852 2500);
DISPLAY 0.872340 (2852 2500);
PAINT GREEN (2852 2500);
DISPLAY INVISIBLE (2852 2500);
FORCEADD TAP..1
R 2
(2850 2700);
FORCEPROP 3 LASTPIN (2900 2700) SIG_NAME P5E_CPU0_P3_TX_DP<11>
J 0
(2910 2710);
DISPLAY 0.659574 (2910 2710);
PAINT MONO (2910 2710);
DISPLAY INVISIBLE (2910 2710);
FORCEPROP 1 LASTPIN (2900 2700) BN 11
J 2
(2912 2708);
DISPLAY 0.680851 (2912 2708);
PAINT GREEN (2912 2708);
FORCEPROP 2 LAST CDS_LIB standard
J 0
(2850 2700);
DISPLAY INVISIBLE (2850 2700);
FORCEPROP 1 LAST BODY_TYPE PLUMBING
J 2
(2850 2750);
DISPLAY 0.872340 (2850 2750);
PAINT GREEN (2850 2750);
DISPLAY INVISIBLE (2850 2750);
FORCEPROP 1 LAST HDL_TAP TRUE
J 2
(2525 2575);
DISPLAY 0.872340 (2525 2575);
DISPLAY INVISIBLE (2525 2575);
FORCEPROP 1 LAST PATH I141
J 2
(2852 2700);
DISPLAY 0.872340 (2852 2700);
PAINT GREEN (2852 2700);
DISPLAY INVISIBLE (2852 2700);
FORCEADD TAP..1
R 2
(2850 2900);
FORCEPROP 3 LASTPIN (2900 2900) SIG_NAME P5E_CPU0_P3_TX_DP<12>
J 0
(2910 2910);
DISPLAY 0.659574 (2910 2910);
PAINT MONO (2910 2910);
DISPLAY INVISIBLE (2910 2910);
FORCEPROP 1 LASTPIN (2900 2900) BN 12
J 2
(2912 2908);
DISPLAY 0.680851 (2912 2908);
PAINT GREEN (2912 2908);
FORCEPROP 2 LAST CDS_LIB standard
J 0
(2850 2900);
DISPLAY INVISIBLE (2850 2900);
FORCEPROP 1 LAST BODY_TYPE PLUMBING
J 2
(2850 2950);
DISPLAY 0.872340 (2850 2950);
PAINT GREEN (2850 2950);
DISPLAY INVISIBLE (2850 2950);
FORCEPROP 1 LAST HDL_TAP TRUE
J 2
(2525 2775);
DISPLAY 0.872340 (2525 2775);
DISPLAY INVISIBLE (2525 2775);
FORCEPROP 1 LAST PATH I142
J 2
(2852 2900);
DISPLAY 0.872340 (2852 2900);
PAINT GREEN (2852 2900);
DISPLAY INVISIBLE (2852 2900);
FORCEADD TAP..1
R 2
(2850 3100);
FORCEPROP 3 LASTPIN (2900 3100) SIG_NAME P5E_CPU0_P3_TX_DP<13>
J 0
(2910 3110);
DISPLAY 0.659574 (2910 3110);
PAINT MONO (2910 3110);
DISPLAY INVISIBLE (2910 3110);
FORCEPROP 1 LASTPIN (2900 3100) BN 13
J 2
(2912 3108);
DISPLAY 0.680851 (2912 3108);
PAINT GREEN (2912 3108);
FORCEPROP 2 LAST CDS_LIB standard
J 0
(2850 3100);
DISPLAY INVISIBLE (2850 3100);
FORCEPROP 1 LAST BODY_TYPE PLUMBING
J 2
(2850 3150);
DISPLAY 0.872340 (2850 3150);
PAINT GREEN (2850 3150);
DISPLAY INVISIBLE (2850 3150);
FORCEPROP 1 LAST HDL_TAP TRUE
J 2
(2525 2975);
DISPLAY 0.872340 (2525 2975);
DISPLAY INVISIBLE (2525 2975);
FORCEPROP 1 LAST PATH I143
J 2
(2852 3100);
DISPLAY 0.872340 (2852 3100);
PAINT GREEN (2852 3100);
DISPLAY INVISIBLE (2852 3100);
FORCEADD TAP..1
R 2
(2850 3300);
FORCEPROP 3 LASTPIN (2900 3300) SIG_NAME P5E_CPU0_P3_TX_DP<14>
J 0
(2910 3310);
DISPLAY 0.659574 (2910 3310);
PAINT MONO (2910 3310);
DISPLAY INVISIBLE (2910 3310);
FORCEPROP 1 LASTPIN (2900 3300) BN 14
J 2
(2912 3308);
DISPLAY 0.680851 (2912 3308);
PAINT GREEN (2912 3308);
FORCEPROP 2 LAST CDS_LIB standard
J 0
(2850 3300);
DISPLAY INVISIBLE (2850 3300);
FORCEPROP 1 LAST BODY_TYPE PLUMBING
J 2
(2850 3350);
DISPLAY 0.872340 (2850 3350);
PAINT GREEN (2850 3350);
DISPLAY INVISIBLE (2850 3350);
FORCEPROP 1 LAST HDL_TAP TRUE
J 2
(2525 3175);
DISPLAY 0.872340 (2525 3175);
DISPLAY INVISIBLE (2525 3175);
FORCEPROP 1 LAST PATH I144
J 2
(2852 3300);
DISPLAY 0.872340 (2852 3300);
PAINT GREEN (2852 3300);
DISPLAY INVISIBLE (2852 3300);
FORCEADD TAP..1
R 2
(2850 3500);
FORCEPROP 3 LASTPIN (2900 3500) SIG_NAME P5E_CPU0_P3_TX_DP<15>
J 0
(2910 3510);
DISPLAY 0.659574 (2910 3510);
PAINT MONO (2910 3510);
DISPLAY INVISIBLE (2910 3510);
FORCEPROP 1 LASTPIN (2900 3500) BN 15
J 2
(2912 3508);
DISPLAY 0.680851 (2912 3508);
PAINT GREEN (2912 3508);
FORCEPROP 2 LAST CDS_LIB standard
J 0
(2850 3500);
DISPLAY INVISIBLE (2850 3500);
FORCEPROP 1 LAST BODY_TYPE PLUMBING
J 2
(2850 3550);
DISPLAY 0.872340 (2850 3550);
PAINT GREEN (2850 3550);
DISPLAY INVISIBLE (2850 3550);
FORCEPROP 1 LAST HDL_TAP TRUE
J 2
(2525 3375);
DISPLAY 0.872340 (2525 3375);
DISPLAY INVISIBLE (2525 3375);
FORCEPROP 1 LAST PATH I145
J 2
(2852 3500);
DISPLAY 0.872340 (2852 3500);
PAINT GREEN (2852 3500);
DISPLAY INVISIBLE (2852 3500);
FORCEADD TAP..1
R 2
(3100 2150);
FORCEPROP 3 LASTPIN (3150 2150) SIG_NAME P5E_CPU0_P3_TX_DN<8>
J 0
(3160 2160);
DISPLAY 0.659574 (3160 2160);
PAINT MONO (3160 2160);
DISPLAY INVISIBLE (3160 2160);
FORCEPROP 1 LASTPIN (3150 2150) BN 8
J 2
(3162 2158);
DISPLAY 0.680851 (3162 2158);
PAINT GREEN (3162 2158);
FORCEPROP 2 LAST CDS_LIB standard
J 0
(3100 2150);
DISPLAY INVISIBLE (3100 2150);
FORCEPROP 1 LAST BODY_TYPE PLUMBING
J 2
(3100 2200);
DISPLAY 0.872340 (3100 2200);
PAINT GREEN (3100 2200);
DISPLAY INVISIBLE (3100 2200);
FORCEPROP 1 LAST HDL_TAP TRUE
J 2
(2775 2025);
DISPLAY 0.872340 (2775 2025);
DISPLAY INVISIBLE (2775 2025);
FORCEPROP 1 LAST PATH I146
J 2
(3102 2150);
DISPLAY 0.872340 (3102 2150);
PAINT GREEN (3102 2150);
DISPLAY INVISIBLE (3102 2150);
FORCEADD TAP..1
R 2
(3100 2350);
FORCEPROP 3 LASTPIN (3150 2350) SIG_NAME P5E_CPU0_P3_TX_DN<9>
J 0
(3160 2360);
DISPLAY 0.659574 (3160 2360);
PAINT MONO (3160 2360);
DISPLAY INVISIBLE (3160 2360);
FORCEPROP 1 LASTPIN (3150 2350) BN 9
J 2
(3162 2358);
DISPLAY 0.680851 (3162 2358);
PAINT GREEN (3162 2358);
FORCEPROP 2 LAST CDS_LIB standard
J 0
(3100 2350);
DISPLAY INVISIBLE (3100 2350);
FORCEPROP 1 LAST BODY_TYPE PLUMBING
J 2
(3100 2400);
DISPLAY 0.872340 (3100 2400);
PAINT GREEN (3100 2400);
DISPLAY INVISIBLE (3100 2400);
FORCEPROP 1 LAST HDL_TAP TRUE
J 2
(2775 2225);
DISPLAY 0.872340 (2775 2225);
DISPLAY INVISIBLE (2775 2225);
FORCEPROP 1 LAST PATH I147
J 2
(3102 2350);
DISPLAY 0.872340 (3102 2350);
PAINT GREEN (3102 2350);
DISPLAY INVISIBLE (3102 2350);
FORCEADD TAP..1
R 2
(3100 2550);
FORCEPROP 3 LASTPIN (3150 2550) SIG_NAME P5E_CPU0_P3_TX_DN<10>
J 0
(3160 2560);
DISPLAY 0.659574 (3160 2560);
PAINT MONO (3160 2560);
DISPLAY INVISIBLE (3160 2560);
FORCEPROP 1 LASTPIN (3150 2550) BN 10
J 2
(3162 2558);
DISPLAY 0.680851 (3162 2558);
PAINT GREEN (3162 2558);
FORCEPROP 2 LAST CDS_LIB standard
J 0
(3100 2550);
DISPLAY INVISIBLE (3100 2550);
FORCEPROP 1 LAST BODY_TYPE PLUMBING
J 2
(3100 2600);
DISPLAY 0.872340 (3100 2600);
PAINT GREEN (3100 2600);
DISPLAY INVISIBLE (3100 2600);
FORCEPROP 1 LAST HDL_TAP TRUE
J 2
(2775 2425);
DISPLAY 0.872340 (2775 2425);
DISPLAY INVISIBLE (2775 2425);
FORCEPROP 1 LAST PATH I148
J 2
(3102 2550);
DISPLAY 0.872340 (3102 2550);
PAINT GREEN (3102 2550);
DISPLAY INVISIBLE (3102 2550);
FORCEADD TAP..1
R 2
(3100 2750);
FORCEPROP 3 LASTPIN (3150 2750) SIG_NAME P5E_CPU0_P3_TX_DN<11>
J 0
(3160 2760);
DISPLAY 0.659574 (3160 2760);
PAINT MONO (3160 2760);
DISPLAY INVISIBLE (3160 2760);
FORCEPROP 1 LASTPIN (3150 2750) BN 11
J 2
(3162 2758);
DISPLAY 0.680851 (3162 2758);
PAINT GREEN (3162 2758);
FORCEPROP 2 LAST CDS_LIB standard
J 0
(3100 2750);
DISPLAY INVISIBLE (3100 2750);
FORCEPROP 1 LAST BODY_TYPE PLUMBING
J 2
(3100 2800);
DISPLAY 0.872340 (3100 2800);
PAINT GREEN (3100 2800);
DISPLAY INVISIBLE (3100 2800);
FORCEPROP 1 LAST HDL_TAP TRUE
J 2
(2775 2625);
DISPLAY 0.872340 (2775 2625);
DISPLAY INVISIBLE (2775 2625);
FORCEPROP 1 LAST PATH I149
J 2
(3102 2750);
DISPLAY 0.872340 (3102 2750);
PAINT GREEN (3102 2750);
DISPLAY INVISIBLE (3102 2750);
FORCEADD TAP..1
R 2
(-1625 1125);
FORCEPROP 3 LASTPIN (-1575 1125) SIG_NAME P5E_CPU0_P2_TX_DP<5>
J 0
(-1565 1135);
DISPLAY 0.659574 (-1565 1135);
PAINT MONO (-1565 1135);
DISPLAY INVISIBLE (-1565 1135);
FORCEPROP 1 LASTPIN (-1575 1125) BN 5
J 2
(-1563 1133);
DISPLAY 0.680851 (-1563 1133);
PAINT GREEN (-1563 1133);
FORCEPROP 2 LAST CDS_LIB standard
J 0
(-1625 1125);
DISPLAY INVISIBLE (-1625 1125);
FORCEPROP 1 LAST BODY_TYPE PLUMBING
J 2
(-1625 1175);
DISPLAY 0.872340 (-1625 1175);
PAINT GREEN (-1625 1175);
DISPLAY INVISIBLE (-1625 1175);
FORCEPROP 1 LAST HDL_TAP TRUE
J 2
(-1950 1000);
DISPLAY 0.872340 (-1950 1000);
DISPLAY INVISIBLE (-1950 1000);
FORCEPROP 1 LAST PATH I15
J 2
(-1623 1125);
DISPLAY 0.872340 (-1623 1125);
PAINT GREEN (-1623 1125);
DISPLAY INVISIBLE (-1623 1125);
FORCEADD TAP..1
R 2
(3100 2950);
FORCEPROP 3 LASTPIN (3150 2950) SIG_NAME P5E_CPU0_P3_TX_DN<12>
J 0
(3160 2960);
DISPLAY 0.659574 (3160 2960);
PAINT MONO (3160 2960);
DISPLAY INVISIBLE (3160 2960);
FORCEPROP 1 LASTPIN (3150 2950) BN 12
J 2
(3162 2958);
DISPLAY 0.680851 (3162 2958);
PAINT GREEN (3162 2958);
FORCEPROP 2 LAST CDS_LIB standard
J 0
(3100 2950);
DISPLAY INVISIBLE (3100 2950);
FORCEPROP 1 LAST BODY_TYPE PLUMBING
J 2
(3100 3000);
DISPLAY 0.872340 (3100 3000);
PAINT GREEN (3100 3000);
DISPLAY INVISIBLE (3100 3000);
FORCEPROP 1 LAST HDL_TAP TRUE
J 2
(2775 2825);
DISPLAY 0.872340 (2775 2825);
DISPLAY INVISIBLE (2775 2825);
FORCEPROP 1 LAST PATH I150
J 2
(3102 2950);
DISPLAY 0.872340 (3102 2950);
PAINT GREEN (3102 2950);
DISPLAY INVISIBLE (3102 2950);
FORCEADD Q_CAP_DIFFBUS..2
R 2
(3825 2150);
FORCEPROP 1 LAST LOCATION C884
J 2
(4059 2167);
DISPLAY 0.723404 (4059 2167);
PAINT GREEN (4059 2167);
FORCEPROP 2 LAST $SEC 1
J 2
(4000 2225);
DISPLAY 0.680851 (4000 2225);
PAINT MONO (4000 2225);
DISPLAY INVISIBLE (4000 2225);
FORCEPROP 2 LAST CDS_SEC 1
J 2
(4000 2225);
DISPLAY 0.680851 (4000 2225);
DISPLAY INVISIBLE (4000 2225);
FORCEPROP 2 LASTPIN (3900 2150) $PN 1
J 0
(3910 2160);
DISPLAY 0.808511 (3910 2160);
FORCEPROP 2 LASTPIN (3750 2150) $PN 2
J 2
(3740 2160);
DISPLAY 0.808511 (3740 2160);
FORCEPROP 2 LAST VALUE DIFF BUS_0.22UF
J 2
(3675 2150);
DISPLAY 0.553191 (3675 2150);
FORCEPROP 1 LAST CDS_LMAN_SYM_OUTLINE -25,50,25,-50
J 2
(3825 2150);
DISPLAY 0.468085 (3825 2150);
PAINT GREEN (3825 2150);
DISPLAY INVISIBLE (3825 2150);
FORCEPROP 2 LAST CDS_LIB pure_quanta
J 2
(3825 2150);
DISPLAY INVISIBLE (3825 2150);
FORCEPROP 1 LAST PIN_NAMES_ROTATE TRUE
J 2
(3825 2150);
DISPLAY 0.489362 (3825 2150);
PAINT GREEN (3825 2150);
DISPLAY INVISIBLE (3825 2150);
FORCEPROP 2 LAST VOLTAGE 6.3V
J 2
(3475 2200);
DISPLAY 0.553191 (3475 2200);
DISPLAY INVISIBLE (3475 2200);
FORCEPROP 1 LAST MATERIAL X6S
J 2
(3834 2229);
DISPLAY 0.574468 (3834 2229);
PAINT GREEN (3834 2229);
DISPLAY INVISIBLE (3834 2229);
FORCEPROP 2 LAST PACK_TYPE C0201
J 2
(3650 2200);
DISPLAY 0.553191 (3650 2200);
DISPLAY INVISIBLE (3650 2200);
FORCEPROP 2 LAST TOLERANCE 20%
J 2
(3750 2200);
DISPLAY 0.553191 (3750 2200);
DISPLAY INVISIBLE (3750 2200);
FORCEPROP 1 LAST PART_NUMBER SP_CH4221MEE01
J 2
(3709 2238);
DISPLAY 0.574468 (3709 2238);
PAINT GREEN (3709 2238);
DISPLAY INVISIBLE (3709 2238);
FORCEPROP 1 LAST LOCATION C884
J 0
(4075 2225);
DISPLAY 1.021277 (4075 2225);
DISPLAY INVISIBLE (4075 2225);
FORCEPROP 1 LAST PATH I151
J 2
(3825 2150);
DISPLAY 0.723404 (3825 2150);
DISPLAY INVISIBLE (3825 2150);
FORCEADD Q_CAP_DIFFBUS..2
R 2
(3825 2100);
FORCEPROP 1 LAST LOCATION C885
J 2
(4059 2117);
DISPLAY 0.723404 (4059 2117);
PAINT GREEN (4059 2117);
FORCEPROP 2 LAST $SEC 1
J 2
(4000 2175);
DISPLAY 0.680851 (4000 2175);
PAINT MONO (4000 2175);
DISPLAY INVISIBLE (4000 2175);
FORCEPROP 2 LAST CDS_SEC 1
J 2
(4000 2175);
DISPLAY 0.680851 (4000 2175);
DISPLAY INVISIBLE (4000 2175);
FORCEPROP 2 LASTPIN (3900 2100) $PN 1
J 0
(3910 2110);
DISPLAY 0.808511 (3910 2110);
FORCEPROP 2 LASTPIN (3750 2100) $PN 2
J 2
(3740 2110);
DISPLAY 0.808511 (3740 2110);
FORCEPROP 2 LAST VALUE DIFF BUS_0.22UF
J 2
(3675 2100);
DISPLAY 0.553191 (3675 2100);
FORCEPROP 1 LAST CDS_LMAN_SYM_OUTLINE -25,50,25,-50
J 2
(3825 2100);
DISPLAY 0.468085 (3825 2100);
PAINT GREEN (3825 2100);
DISPLAY INVISIBLE (3825 2100);
FORCEPROP 2 LAST CDS_LIB pure_quanta
J 2
(3825 2100);
DISPLAY INVISIBLE (3825 2100);
FORCEPROP 1 LAST PIN_NAMES_ROTATE TRUE
J 2
(3825 2100);
DISPLAY 0.489362 (3825 2100);
PAINT GREEN (3825 2100);
DISPLAY INVISIBLE (3825 2100);
FORCEPROP 2 LAST VOLTAGE 6.3V
J 2
(3475 2150);
DISPLAY 0.553191 (3475 2150);
DISPLAY INVISIBLE (3475 2150);
FORCEPROP 1 LAST MATERIAL X6S
J 2
(3834 2179);
DISPLAY 0.574468 (3834 2179);
PAINT GREEN (3834 2179);
DISPLAY INVISIBLE (3834 2179);
FORCEPROP 2 LAST PACK_TYPE C0201
J 2
(3650 2150);
DISPLAY 0.553191 (3650 2150);
DISPLAY INVISIBLE (3650 2150);
FORCEPROP 2 LAST TOLERANCE 20%
J 2
(3750 2150);
DISPLAY 0.553191 (3750 2150);
DISPLAY INVISIBLE (3750 2150);
FORCEPROP 1 LAST PART_NUMBER SP_CH4221MEE01
J 2
(3709 2188);
DISPLAY 0.574468 (3709 2188);
PAINT GREEN (3709 2188);
DISPLAY INVISIBLE (3709 2188);
FORCEPROP 1 LAST LOCATION C885
J 0
(4075 2175);
DISPLAY 1.021277 (4075 2175);
DISPLAY INVISIBLE (4075 2175);
FORCEPROP 1 LAST PATH I152
J 2
(3825 2100);
DISPLAY 0.723404 (3825 2100);
DISPLAY INVISIBLE (3825 2100);
FORCEADD Q_CAP_DIFFBUS..2
R 2
(3825 2300);
FORCEPROP 1 LAST LOCATION C883
J 2
(4059 2317);
DISPLAY 0.723404 (4059 2317);
PAINT GREEN (4059 2317);
FORCEPROP 2 LAST $SEC 1
J 2
(4000 2375);
DISPLAY 0.680851 (4000 2375);
PAINT MONO (4000 2375);
DISPLAY INVISIBLE (4000 2375);
FORCEPROP 2 LAST CDS_SEC 1
J 2
(4000 2375);
DISPLAY 0.680851 (4000 2375);
DISPLAY INVISIBLE (4000 2375);
FORCEPROP 2 LASTPIN (3900 2300) $PN 1
J 0
(3910 2310);
DISPLAY 0.808511 (3910 2310);
FORCEPROP 2 LASTPIN (3750 2300) $PN 2
J 2
(3740 2310);
DISPLAY 0.808511 (3740 2310);
FORCEPROP 2 LAST VALUE DIFF BUS_0.22UF
J 2
(3675 2300);
DISPLAY 0.553191 (3675 2300);
FORCEPROP 1 LAST CDS_LMAN_SYM_OUTLINE -25,50,25,-50
J 2
(3825 2300);
DISPLAY 0.468085 (3825 2300);
PAINT GREEN (3825 2300);
DISPLAY INVISIBLE (3825 2300);
FORCEPROP 2 LAST CDS_LIB pure_quanta
J 2
(3825 2300);
DISPLAY INVISIBLE (3825 2300);
FORCEPROP 1 LAST PIN_NAMES_ROTATE TRUE
J 2
(3825 2300);
DISPLAY 0.489362 (3825 2300);
PAINT GREEN (3825 2300);
DISPLAY INVISIBLE (3825 2300);
FORCEPROP 2 LAST VOLTAGE 6.3V
J 2
(3475 2350);
DISPLAY 0.553191 (3475 2350);
DISPLAY INVISIBLE (3475 2350);
FORCEPROP 1 LAST MATERIAL X6S
J 2
(3834 2379);
DISPLAY 0.574468 (3834 2379);
PAINT GREEN (3834 2379);
DISPLAY INVISIBLE (3834 2379);
FORCEPROP 2 LAST PACK_TYPE C0201
J 2
(3650 2350);
DISPLAY 0.553191 (3650 2350);
DISPLAY INVISIBLE (3650 2350);
FORCEPROP 2 LAST TOLERANCE 20%
J 2
(3750 2350);
DISPLAY 0.553191 (3750 2350);
DISPLAY INVISIBLE (3750 2350);
FORCEPROP 1 LAST PART_NUMBER SP_CH4221MEE01
J 2
(3709 2388);
DISPLAY 0.574468 (3709 2388);
PAINT GREEN (3709 2388);
DISPLAY INVISIBLE (3709 2388);
FORCEPROP 1 LAST LOCATION C883
J 0
(4075 2375);
DISPLAY 1.021277 (4075 2375);
DISPLAY INVISIBLE (4075 2375);
FORCEPROP 1 LAST PATH I153
J 2
(3825 2300);
DISPLAY 0.723404 (3825 2300);
DISPLAY INVISIBLE (3825 2300);
FORCEADD Q_CAP_DIFFBUS..2
R 2
(3825 2350);
FORCEPROP 1 LAST LOCATION C882
J 2
(4059 2367);
DISPLAY 0.723404 (4059 2367);
PAINT GREEN (4059 2367);
FORCEPROP 2 LAST $SEC 1
J 2
(4000 2425);
DISPLAY 0.680851 (4000 2425);
PAINT MONO (4000 2425);
DISPLAY INVISIBLE (4000 2425);
FORCEPROP 2 LAST CDS_SEC 1
J 2
(4000 2425);
DISPLAY 0.680851 (4000 2425);
DISPLAY INVISIBLE (4000 2425);
FORCEPROP 2 LASTPIN (3900 2350) $PN 1
J 0
(3910 2360);
DISPLAY 0.808511 (3910 2360);
FORCEPROP 2 LASTPIN (3750 2350) $PN 2
J 2
(3740 2360);
DISPLAY 0.808511 (3740 2360);
FORCEPROP 2 LAST VALUE DIFF BUS_0.22UF
J 2
(3675 2350);
DISPLAY 0.553191 (3675 2350);
FORCEPROP 2 LAST CDS_LIB pure_quanta
J 2
(3825 2350);
DISPLAY INVISIBLE (3825 2350);
FORCEPROP 1 LAST CDS_LMAN_SYM_OUTLINE -25,50,25,-50
J 2
(3825 2350);
DISPLAY 0.468085 (3825 2350);
PAINT GREEN (3825 2350);
DISPLAY INVISIBLE (3825 2350);
FORCEPROP 1 LAST PIN_NAMES_ROTATE TRUE
J 2
(3825 2350);
DISPLAY 0.489362 (3825 2350);
PAINT GREEN (3825 2350);
DISPLAY INVISIBLE (3825 2350);
FORCEPROP 2 LAST VOLTAGE 6.3V
J 2
(3475 2400);
DISPLAY 0.553191 (3475 2400);
DISPLAY INVISIBLE (3475 2400);
FORCEPROP 1 LAST MATERIAL X6S
J 2
(3834 2429);
DISPLAY 0.574468 (3834 2429);
PAINT GREEN (3834 2429);
DISPLAY INVISIBLE (3834 2429);
FORCEPROP 2 LAST PACK_TYPE C0201
J 2
(3650 2400);
DISPLAY 0.553191 (3650 2400);
DISPLAY INVISIBLE (3650 2400);
FORCEPROP 2 LAST TOLERANCE 20%
J 2
(3750 2400);
DISPLAY 0.553191 (3750 2400);
DISPLAY INVISIBLE (3750 2400);
FORCEPROP 1 LAST PART_NUMBER SP_CH4221MEE01
J 2
(3709 2438);
DISPLAY 0.574468 (3709 2438);
PAINT GREEN (3709 2438);
DISPLAY INVISIBLE (3709 2438);
FORCEPROP 1 LAST LOCATION C882
J 0
(4075 2425);
DISPLAY 1.021277 (4075 2425);
DISPLAY INVISIBLE (4075 2425);
FORCEPROP 1 LAST PATH I154
J 2
(3825 2350);
DISPLAY 0.723404 (3825 2350);
DISPLAY INVISIBLE (3825 2350);
FORCEADD Q_CAP_DIFFBUS..2
R 2
(3825 2500);
FORCEPROP 1 LAST LOCATION C881
J 2
(4059 2517);
DISPLAY 0.723404 (4059 2517);
PAINT GREEN (4059 2517);
FORCEPROP 2 LAST $SEC 1
J 2
(4000 2575);
DISPLAY 0.680851 (4000 2575);
PAINT MONO (4000 2575);
DISPLAY INVISIBLE (4000 2575);
FORCEPROP 2 LAST CDS_SEC 1
J 2
(4000 2575);
DISPLAY 0.680851 (4000 2575);
DISPLAY INVISIBLE (4000 2575);
FORCEPROP 2 LASTPIN (3900 2500) $PN 1
J 0
(3910 2510);
DISPLAY 0.808511 (3910 2510);
FORCEPROP 2 LASTPIN (3750 2500) $PN 2
J 2
(3740 2510);
DISPLAY 0.808511 (3740 2510);
FORCEPROP 2 LAST VALUE DIFF BUS_0.22UF
J 2
(3675 2500);
DISPLAY 0.553191 (3675 2500);
FORCEPROP 1 LAST CDS_LMAN_SYM_OUTLINE -25,50,25,-50
J 2
(3825 2500);
DISPLAY 0.468085 (3825 2500);
PAINT GREEN (3825 2500);
DISPLAY INVISIBLE (3825 2500);
FORCEPROP 2 LAST CDS_LIB pure_quanta
J 2
(3825 2500);
DISPLAY INVISIBLE (3825 2500);
FORCEPROP 1 LAST PIN_NAMES_ROTATE TRUE
J 2
(3825 2500);
DISPLAY 0.489362 (3825 2500);
PAINT GREEN (3825 2500);
DISPLAY INVISIBLE (3825 2500);
FORCEPROP 2 LAST VOLTAGE 6.3V
J 2
(3475 2550);
DISPLAY 0.553191 (3475 2550);
DISPLAY INVISIBLE (3475 2550);
FORCEPROP 1 LAST MATERIAL X6S
J 2
(3834 2579);
DISPLAY 0.574468 (3834 2579);
PAINT GREEN (3834 2579);
DISPLAY INVISIBLE (3834 2579);
FORCEPROP 2 LAST PACK_TYPE C0201
J 2
(3650 2550);
DISPLAY 0.553191 (3650 2550);
DISPLAY INVISIBLE (3650 2550);
FORCEPROP 2 LAST TOLERANCE 20%
J 2
(3750 2550);
DISPLAY 0.553191 (3750 2550);
DISPLAY INVISIBLE (3750 2550);
FORCEPROP 1 LAST PART_NUMBER SP_CH4221MEE01
J 2
(3709 2588);
DISPLAY 0.574468 (3709 2588);
PAINT GREEN (3709 2588);
DISPLAY INVISIBLE (3709 2588);
FORCEPROP 1 LAST LOCATION C881
J 0
(4075 2575);
DISPLAY 1.021277 (4075 2575);
DISPLAY INVISIBLE (4075 2575);
FORCEPROP 1 LAST PATH I155
J 2
(3825 2500);
DISPLAY 0.723404 (3825 2500);
DISPLAY INVISIBLE (3825 2500);
FORCEADD Q_CAP_DIFFBUS..2
R 2
(3825 2550);
FORCEPROP 1 LAST LOCATION C880
J 2
(4059 2567);
DISPLAY 0.723404 (4059 2567);
PAINT GREEN (4059 2567);
FORCEPROP 2 LAST $SEC 1
J 2
(4000 2625);
DISPLAY 0.680851 (4000 2625);
PAINT MONO (4000 2625);
DISPLAY INVISIBLE (4000 2625);
FORCEPROP 2 LAST CDS_SEC 1
J 2
(4000 2625);
DISPLAY 0.680851 (4000 2625);
DISPLAY INVISIBLE (4000 2625);
FORCEPROP 2 LASTPIN (3900 2550) $PN 1
J 0
(3910 2560);
DISPLAY 0.808511 (3910 2560);
FORCEPROP 2 LASTPIN (3750 2550) $PN 2
J 2
(3740 2560);
DISPLAY 0.808511 (3740 2560);
FORCEPROP 2 LAST VALUE DIFF BUS_0.22UF
J 2
(3675 2550);
DISPLAY 0.553191 (3675 2550);
FORCEPROP 1 LAST CDS_LMAN_SYM_OUTLINE -25,50,25,-50
J 2
(3825 2550);
DISPLAY 0.468085 (3825 2550);
PAINT GREEN (3825 2550);
DISPLAY INVISIBLE (3825 2550);
FORCEPROP 2 LAST CDS_LIB pure_quanta
J 2
(3825 2550);
DISPLAY INVISIBLE (3825 2550);
FORCEPROP 1 LAST PIN_NAMES_ROTATE TRUE
J 2
(3825 2550);
DISPLAY 0.489362 (3825 2550);
PAINT GREEN (3825 2550);
DISPLAY INVISIBLE (3825 2550);
FORCEPROP 2 LAST VOLTAGE 6.3V
J 2
(3475 2600);
DISPLAY 0.553191 (3475 2600);
DISPLAY INVISIBLE (3475 2600);
FORCEPROP 1 LAST MATERIAL X6S
J 2
(3834 2629);
DISPLAY 0.574468 (3834 2629);
PAINT GREEN (3834 2629);
DISPLAY INVISIBLE (3834 2629);
FORCEPROP 2 LAST PACK_TYPE C0201
J 2
(3650 2600);
DISPLAY 0.553191 (3650 2600);
DISPLAY INVISIBLE (3650 2600);
FORCEPROP 2 LAST TOLERANCE 20%
J 2
(3750 2600);
DISPLAY 0.553191 (3750 2600);
DISPLAY INVISIBLE (3750 2600);
FORCEPROP 1 LAST PART_NUMBER SP_CH4221MEE01
J 2
(3709 2638);
DISPLAY 0.574468 (3709 2638);
PAINT GREEN (3709 2638);
DISPLAY INVISIBLE (3709 2638);
FORCEPROP 1 LAST LOCATION C880
J 0
(4075 2625);
DISPLAY 1.021277 (4075 2625);
DISPLAY INVISIBLE (4075 2625);
FORCEPROP 1 LAST PATH I156
J 2
(3825 2550);
DISPLAY 0.723404 (3825 2550);
DISPLAY INVISIBLE (3825 2550);
FORCEADD Q_CAP_DIFFBUS..2
R 2
(3825 2750);
FORCEPROP 1 LAST LOCATION C878
J 2
(4059 2767);
DISPLAY 0.723404 (4059 2767);
PAINT GREEN (4059 2767);
FORCEPROP 2 LAST $SEC 1
J 2
(4000 2825);
DISPLAY 0.680851 (4000 2825);
PAINT MONO (4000 2825);
DISPLAY INVISIBLE (4000 2825);
FORCEPROP 2 LAST CDS_SEC 1
J 2
(4000 2825);
DISPLAY 0.680851 (4000 2825);
DISPLAY INVISIBLE (4000 2825);
FORCEPROP 2 LASTPIN (3900 2750) $PN 1
J 0
(3910 2760);
DISPLAY 0.808511 (3910 2760);
FORCEPROP 2 LASTPIN (3750 2750) $PN 2
J 2
(3740 2760);
DISPLAY 0.808511 (3740 2760);
FORCEPROP 2 LAST VALUE DIFF BUS_0.22UF
J 2
(3675 2750);
DISPLAY 0.553191 (3675 2750);
FORCEPROP 2 LAST CDS_LIB pure_quanta
J 2
(3825 2750);
DISPLAY INVISIBLE (3825 2750);
FORCEPROP 1 LAST CDS_LMAN_SYM_OUTLINE -25,50,25,-50
J 2
(3825 2750);
DISPLAY 0.468085 (3825 2750);
PAINT GREEN (3825 2750);
DISPLAY INVISIBLE (3825 2750);
FORCEPROP 1 LAST PIN_NAMES_ROTATE TRUE
J 2
(3825 2750);
DISPLAY 0.489362 (3825 2750);
PAINT GREEN (3825 2750);
DISPLAY INVISIBLE (3825 2750);
FORCEPROP 2 LAST VOLTAGE 6.3V
J 2
(3475 2800);
DISPLAY 0.553191 (3475 2800);
DISPLAY INVISIBLE (3475 2800);
FORCEPROP 1 LAST MATERIAL X6S
J 2
(3834 2829);
DISPLAY 0.574468 (3834 2829);
PAINT GREEN (3834 2829);
DISPLAY INVISIBLE (3834 2829);
FORCEPROP 2 LAST PACK_TYPE C0201
J 2
(3650 2800);
DISPLAY 0.553191 (3650 2800);
DISPLAY INVISIBLE (3650 2800);
FORCEPROP 2 LAST TOLERANCE 20%
J 2
(3750 2800);
DISPLAY 0.553191 (3750 2800);
DISPLAY INVISIBLE (3750 2800);
FORCEPROP 1 LAST PART_NUMBER SP_CH4221MEE01
J 2
(3709 2838);
DISPLAY 0.574468 (3709 2838);
PAINT GREEN (3709 2838);
DISPLAY INVISIBLE (3709 2838);
FORCEPROP 1 LAST LOCATION C878
J 0
(4075 2825);
DISPLAY 1.021277 (4075 2825);
DISPLAY INVISIBLE (4075 2825);
FORCEPROP 1 LAST PATH I157
J 2
(3825 2750);
DISPLAY 0.723404 (3825 2750);
DISPLAY INVISIBLE (3825 2750);
FORCEADD Q_CAP_DIFFBUS..2
R 2
(3825 2700);
FORCEPROP 1 LAST LOCATION C879
J 2
(4059 2717);
DISPLAY 0.723404 (4059 2717);
PAINT GREEN (4059 2717);
FORCEPROP 2 LAST $SEC 1
J 2
(4000 2775);
DISPLAY 0.680851 (4000 2775);
PAINT MONO (4000 2775);
DISPLAY INVISIBLE (4000 2775);
FORCEPROP 2 LAST CDS_SEC 1
J 2
(4000 2775);
DISPLAY 0.680851 (4000 2775);
DISPLAY INVISIBLE (4000 2775);
FORCEPROP 2 LASTPIN (3900 2700) $PN 1
J 0
(3910 2710);
DISPLAY 0.808511 (3910 2710);
FORCEPROP 2 LASTPIN (3750 2700) $PN 2
J 2
(3740 2710);
DISPLAY 0.808511 (3740 2710);
FORCEPROP 2 LAST VALUE DIFF BUS_0.22UF
J 2
(3675 2700);
DISPLAY 0.553191 (3675 2700);
FORCEPROP 2 LAST CDS_LIB pure_quanta
J 2
(3825 2700);
DISPLAY INVISIBLE (3825 2700);
FORCEPROP 1 LAST CDS_LMAN_SYM_OUTLINE -25,50,25,-50
J 2
(3825 2700);
DISPLAY 0.468085 (3825 2700);
PAINT GREEN (3825 2700);
DISPLAY INVISIBLE (3825 2700);
FORCEPROP 1 LAST PIN_NAMES_ROTATE TRUE
J 2
(3825 2700);
DISPLAY 0.489362 (3825 2700);
PAINT GREEN (3825 2700);
DISPLAY INVISIBLE (3825 2700);
FORCEPROP 2 LAST VOLTAGE 6.3V
J 2
(3475 2750);
DISPLAY 0.553191 (3475 2750);
DISPLAY INVISIBLE (3475 2750);
FORCEPROP 1 LAST MATERIAL X6S
J 2
(3834 2779);
DISPLAY 0.574468 (3834 2779);
PAINT GREEN (3834 2779);
DISPLAY INVISIBLE (3834 2779);
FORCEPROP 2 LAST PACK_TYPE C0201
J 2
(3650 2750);
DISPLAY 0.553191 (3650 2750);
DISPLAY INVISIBLE (3650 2750);
FORCEPROP 2 LAST TOLERANCE 20%
J 2
(3750 2750);
DISPLAY 0.553191 (3750 2750);
DISPLAY INVISIBLE (3750 2750);
FORCEPROP 1 LAST PART_NUMBER SP_CH4221MEE01
J 2
(3709 2788);
DISPLAY 0.574468 (3709 2788);
PAINT GREEN (3709 2788);
DISPLAY INVISIBLE (3709 2788);
FORCEPROP 1 LAST LOCATION C879
J 0
(4075 2775);
DISPLAY 1.021277 (4075 2775);
DISPLAY INVISIBLE (4075 2775);
FORCEPROP 1 LAST PATH I158
J 2
(3825 2700);
DISPLAY 0.723404 (3825 2700);
DISPLAY INVISIBLE (3825 2700);
FORCEADD Q_CAP_DIFFBUS..2
R 2
(3825 2900);
FORCEPROP 1 LAST LOCATION C877
J 2
(4059 2917);
DISPLAY 0.723404 (4059 2917);
PAINT GREEN (4059 2917);
FORCEPROP 2 LAST $SEC 1
J 2
(4000 2975);
DISPLAY 0.680851 (4000 2975);
PAINT MONO (4000 2975);
DISPLAY INVISIBLE (4000 2975);
FORCEPROP 2 LAST CDS_SEC 1
J 2
(4000 2975);
DISPLAY 0.680851 (4000 2975);
DISPLAY INVISIBLE (4000 2975);
FORCEPROP 2 LASTPIN (3900 2900) $PN 1
J 0
(3910 2910);
DISPLAY 0.808511 (3910 2910);
FORCEPROP 2 LASTPIN (3750 2900) $PN 2
J 2
(3740 2910);
DISPLAY 0.808511 (3740 2910);
FORCEPROP 2 LAST VALUE DIFF BUS_0.22UF
J 2
(3675 2900);
DISPLAY 0.553191 (3675 2900);
FORCEPROP 1 LAST CDS_LMAN_SYM_OUTLINE -25,50,25,-50
J 2
(3825 2900);
DISPLAY 0.468085 (3825 2900);
PAINT GREEN (3825 2900);
DISPLAY INVISIBLE (3825 2900);
FORCEPROP 2 LAST CDS_LIB pure_quanta
J 2
(3825 2900);
DISPLAY INVISIBLE (3825 2900);
FORCEPROP 1 LAST PIN_NAMES_ROTATE TRUE
J 2
(3825 2900);
DISPLAY 0.489362 (3825 2900);
PAINT GREEN (3825 2900);
DISPLAY INVISIBLE (3825 2900);
FORCEPROP 2 LAST VOLTAGE 6.3V
J 2
(3475 2950);
DISPLAY 0.553191 (3475 2950);
DISPLAY INVISIBLE (3475 2950);
FORCEPROP 1 LAST MATERIAL X6S
J 2
(3834 2979);
DISPLAY 0.574468 (3834 2979);
PAINT GREEN (3834 2979);
DISPLAY INVISIBLE (3834 2979);
FORCEPROP 2 LAST PACK_TYPE C0201
J 2
(3650 2950);
DISPLAY 0.553191 (3650 2950);
DISPLAY INVISIBLE (3650 2950);
FORCEPROP 2 LAST TOLERANCE 20%
J 2
(3750 2950);
DISPLAY 0.553191 (3750 2950);
DISPLAY INVISIBLE (3750 2950);
FORCEPROP 1 LAST PART_NUMBER SP_CH4221MEE01
J 2
(3709 2988);
DISPLAY 0.574468 (3709 2988);
PAINT GREEN (3709 2988);
DISPLAY INVISIBLE (3709 2988);
FORCEPROP 1 LAST LOCATION C877
J 0
(4075 2975);
DISPLAY 1.021277 (4075 2975);
DISPLAY INVISIBLE (4075 2975);
FORCEPROP 1 LAST PATH I159
J 2
(3825 2900);
DISPLAY 0.723404 (3825 2900);
DISPLAY INVISIBLE (3825 2900);
FORCEADD TAP..1
R 2
(-1625 1325);
FORCEPROP 3 LASTPIN (-1575 1325) SIG_NAME P5E_CPU0_P2_TX_DP<6>
J 0
(-1565 1335);
DISPLAY 0.659574 (-1565 1335);
PAINT MONO (-1565 1335);
DISPLAY INVISIBLE (-1565 1335);
FORCEPROP 1 LASTPIN (-1575 1325) BN 6
J 2
(-1563 1333);
DISPLAY 0.680851 (-1563 1333);
PAINT GREEN (-1563 1333);
FORCEPROP 2 LAST CDS_LIB standard
J 0
(-1625 1325);
DISPLAY INVISIBLE (-1625 1325);
FORCEPROP 1 LAST BODY_TYPE PLUMBING
J 2
(-1625 1375);
DISPLAY 0.872340 (-1625 1375);
PAINT GREEN (-1625 1375);
DISPLAY INVISIBLE (-1625 1375);
FORCEPROP 1 LAST HDL_TAP TRUE
J 2
(-1950 1200);
DISPLAY 0.872340 (-1950 1200);
DISPLAY INVISIBLE (-1950 1200);
FORCEPROP 1 LAST PATH I16
J 2
(-1623 1325);
DISPLAY 0.872340 (-1623 1325);
PAINT GREEN (-1623 1325);
DISPLAY INVISIBLE (-1623 1325);
FORCEADD Q_CAP_DIFFBUS..2
R 2
(3825 2950);
FORCEPROP 1 LAST LOCATION C876
J 2
(4059 2967);
DISPLAY 0.723404 (4059 2967);
PAINT GREEN (4059 2967);
FORCEPROP 2 LAST $SEC 1
J 2
(4000 3025);
DISPLAY 0.680851 (4000 3025);
PAINT MONO (4000 3025);
DISPLAY INVISIBLE (4000 3025);
FORCEPROP 2 LAST CDS_SEC 1
J 2
(4000 3025);
DISPLAY 0.680851 (4000 3025);
DISPLAY INVISIBLE (4000 3025);
FORCEPROP 2 LASTPIN (3900 2950) $PN 1
J 0
(3910 2960);
DISPLAY 0.808511 (3910 2960);
FORCEPROP 2 LASTPIN (3750 2950) $PN 2
J 2
(3740 2960);
DISPLAY 0.808511 (3740 2960);
FORCEPROP 2 LAST VALUE DIFF BUS_0.22UF
J 2
(3675 2950);
DISPLAY 0.553191 (3675 2950);
FORCEPROP 1 LAST CDS_LMAN_SYM_OUTLINE -25,50,25,-50
J 2
(3825 2950);
DISPLAY 0.468085 (3825 2950);
PAINT GREEN (3825 2950);
DISPLAY INVISIBLE (3825 2950);
FORCEPROP 2 LAST CDS_LIB pure_quanta
J 2
(3825 2950);
DISPLAY INVISIBLE (3825 2950);
FORCEPROP 1 LAST PIN_NAMES_ROTATE TRUE
J 2
(3825 2950);
DISPLAY 0.489362 (3825 2950);
PAINT GREEN (3825 2950);
DISPLAY INVISIBLE (3825 2950);
FORCEPROP 2 LAST VOLTAGE 6.3V
J 2
(3475 3000);
DISPLAY 0.553191 (3475 3000);
DISPLAY INVISIBLE (3475 3000);
FORCEPROP 1 LAST MATERIAL X6S
J 2
(3834 3029);
DISPLAY 0.574468 (3834 3029);
PAINT GREEN (3834 3029);
DISPLAY INVISIBLE (3834 3029);
FORCEPROP 2 LAST PACK_TYPE C0201
J 2
(3650 3000);
DISPLAY 0.553191 (3650 3000);
DISPLAY INVISIBLE (3650 3000);
FORCEPROP 2 LAST TOLERANCE 20%
J 2
(3750 3000);
DISPLAY 0.553191 (3750 3000);
DISPLAY INVISIBLE (3750 3000);
FORCEPROP 1 LAST PART_NUMBER SP_CH4221MEE01
J 2
(3709 3038);
DISPLAY 0.574468 (3709 3038);
PAINT GREEN (3709 3038);
DISPLAY INVISIBLE (3709 3038);
FORCEPROP 1 LAST LOCATION C876
J 0
(4075 3025);
DISPLAY 1.021277 (4075 3025);
DISPLAY INVISIBLE (4075 3025);
FORCEPROP 1 LAST PATH I160
J 2
(3825 2950);
DISPLAY 0.723404 (3825 2950);
DISPLAY INVISIBLE (3825 2950);
FORCEADD TAP..1
R 2
(3100 3150);
FORCEPROP 3 LASTPIN (3150 3150) SIG_NAME P5E_CPU0_P3_TX_DN<13>
J 0
(3160 3160);
DISPLAY 0.659574 (3160 3160);
PAINT MONO (3160 3160);
DISPLAY INVISIBLE (3160 3160);
FORCEPROP 1 LASTPIN (3150 3150) BN 13
J 2
(3162 3158);
DISPLAY 0.680851 (3162 3158);
PAINT GREEN (3162 3158);
FORCEPROP 2 LAST CDS_LIB standard
J 0
(3100 3150);
DISPLAY INVISIBLE (3100 3150);
FORCEPROP 1 LAST BODY_TYPE PLUMBING
J 2
(3100 3200);
DISPLAY 0.872340 (3100 3200);
PAINT GREEN (3100 3200);
DISPLAY INVISIBLE (3100 3200);
FORCEPROP 1 LAST HDL_TAP TRUE
J 2
(2775 3025);
DISPLAY 0.872340 (2775 3025);
DISPLAY INVISIBLE (2775 3025);
FORCEPROP 1 LAST PATH I161
J 2
(3102 3150);
DISPLAY 0.872340 (3102 3150);
PAINT GREEN (3102 3150);
DISPLAY INVISIBLE (3102 3150);
FORCEADD TAP..1
R 2
(3100 3350);
FORCEPROP 3 LASTPIN (3150 3350) SIG_NAME P5E_CPU0_P3_TX_DN<14>
J 0
(3160 3360);
DISPLAY 0.659574 (3160 3360);
PAINT MONO (3160 3360);
DISPLAY INVISIBLE (3160 3360);
FORCEPROP 1 LASTPIN (3150 3350) BN 14
J 2
(3162 3358);
DISPLAY 0.680851 (3162 3358);
PAINT GREEN (3162 3358);
FORCEPROP 2 LAST CDS_LIB standard
J 0
(3100 3350);
DISPLAY INVISIBLE (3100 3350);
FORCEPROP 1 LAST BODY_TYPE PLUMBING
J 2
(3100 3400);
DISPLAY 0.872340 (3100 3400);
PAINT GREEN (3100 3400);
DISPLAY INVISIBLE (3100 3400);
FORCEPROP 1 LAST HDL_TAP TRUE
J 2
(2775 3225);
DISPLAY 0.872340 (2775 3225);
DISPLAY INVISIBLE (2775 3225);
FORCEPROP 1 LAST PATH I162
J 2
(3102 3350);
DISPLAY 0.872340 (3102 3350);
PAINT GREEN (3102 3350);
DISPLAY INVISIBLE (3102 3350);
FORCEADD TAP..1
R 2
(3100 3550);
FORCEPROP 3 LASTPIN (3150 3550) SIG_NAME P5E_CPU0_P3_TX_DN<15>
J 0
(3160 3560);
DISPLAY 0.659574 (3160 3560);
PAINT MONO (3160 3560);
DISPLAY INVISIBLE (3160 3560);
FORCEPROP 1 LASTPIN (3150 3550) BN 15
J 2
(3162 3558);
DISPLAY 0.680851 (3162 3558);
PAINT GREEN (3162 3558);
FORCEPROP 2 LAST CDS_LIB standard
J 0
(3100 3550);
DISPLAY INVISIBLE (3100 3550);
FORCEPROP 1 LAST BODY_TYPE PLUMBING
J 2
(3100 3600);
DISPLAY 0.872340 (3100 3600);
PAINT GREEN (3100 3600);
DISPLAY INVISIBLE (3100 3600);
FORCEPROP 1 LAST HDL_TAP TRUE
J 2
(2775 3425);
DISPLAY 0.872340 (2775 3425);
DISPLAY INVISIBLE (2775 3425);
FORCEPROP 1 LAST PATH I163
J 2
(3102 3550);
DISPLAY 0.872340 (3102 3550);
PAINT GREEN (3102 3550);
DISPLAY INVISIBLE (3102 3550);
FORCEADD Q_CAP_DIFFBUS..2
R 2
(3825 3100);
FORCEPROP 1 LAST LOCATION C875
J 2
(4059 3117);
DISPLAY 0.723404 (4059 3117);
PAINT GREEN (4059 3117);
FORCEPROP 2 LAST $SEC 1
J 2
(4000 3175);
DISPLAY 0.680851 (4000 3175);
PAINT MONO (4000 3175);
DISPLAY INVISIBLE (4000 3175);
FORCEPROP 2 LAST CDS_SEC 1
J 2
(4000 3175);
DISPLAY 0.680851 (4000 3175);
DISPLAY INVISIBLE (4000 3175);
FORCEPROP 2 LASTPIN (3900 3100) $PN 1
J 0
(3910 3110);
DISPLAY 0.808511 (3910 3110);
FORCEPROP 2 LASTPIN (3750 3100) $PN 2
J 2
(3740 3110);
DISPLAY 0.808511 (3740 3110);
FORCEPROP 2 LAST VALUE DIFF BUS_0.22UF
J 2
(3675 3100);
DISPLAY 0.553191 (3675 3100);
FORCEPROP 1 LAST CDS_LMAN_SYM_OUTLINE -25,50,25,-50
J 2
(3825 3100);
DISPLAY 0.468085 (3825 3100);
PAINT GREEN (3825 3100);
DISPLAY INVISIBLE (3825 3100);
FORCEPROP 2 LAST CDS_LIB pure_quanta
J 2
(3825 3100);
DISPLAY INVISIBLE (3825 3100);
FORCEPROP 1 LAST PIN_NAMES_ROTATE TRUE
J 2
(3825 3100);
DISPLAY 0.489362 (3825 3100);
PAINT GREEN (3825 3100);
DISPLAY INVISIBLE (3825 3100);
FORCEPROP 2 LAST VOLTAGE 6.3V
J 2
(3475 3150);
DISPLAY 0.553191 (3475 3150);
DISPLAY INVISIBLE (3475 3150);
FORCEPROP 1 LAST MATERIAL X6S
J 2
(3834 3179);
DISPLAY 0.574468 (3834 3179);
PAINT GREEN (3834 3179);
DISPLAY INVISIBLE (3834 3179);
FORCEPROP 2 LAST PACK_TYPE C0201
J 2
(3650 3150);
DISPLAY 0.553191 (3650 3150);
DISPLAY INVISIBLE (3650 3150);
FORCEPROP 2 LAST TOLERANCE 20%
J 2
(3750 3150);
DISPLAY 0.553191 (3750 3150);
DISPLAY INVISIBLE (3750 3150);
FORCEPROP 1 LAST PART_NUMBER SP_CH4221MEE01
J 2
(3709 3188);
DISPLAY 0.574468 (3709 3188);
PAINT GREEN (3709 3188);
DISPLAY INVISIBLE (3709 3188);
FORCEPROP 1 LAST LOCATION C875
J 0
(4075 3175);
DISPLAY 1.021277 (4075 3175);
DISPLAY INVISIBLE (4075 3175);
FORCEPROP 1 LAST PATH I164
J 2
(3825 3100);
DISPLAY 0.723404 (3825 3100);
DISPLAY INVISIBLE (3825 3100);
FORCEADD Q_CAP_DIFFBUS..2
R 2
(3825 3150);
FORCEPROP 1 LAST LOCATION C874
J 2
(4059 3167);
DISPLAY 0.723404 (4059 3167);
PAINT GREEN (4059 3167);
FORCEPROP 2 LAST $SEC 1
J 2
(4000 3225);
DISPLAY 0.680851 (4000 3225);
PAINT MONO (4000 3225);
DISPLAY INVISIBLE (4000 3225);
FORCEPROP 2 LAST CDS_SEC 1
J 2
(4000 3225);
DISPLAY 0.680851 (4000 3225);
DISPLAY INVISIBLE (4000 3225);
FORCEPROP 2 LASTPIN (3900 3150) $PN 1
J 0
(3910 3160);
DISPLAY 0.808511 (3910 3160);
FORCEPROP 2 LASTPIN (3750 3150) $PN 2
J 2
(3740 3160);
DISPLAY 0.808511 (3740 3160);
FORCEPROP 2 LAST VALUE DIFF BUS_0.22UF
J 2
(3675 3150);
DISPLAY 0.553191 (3675 3150);
FORCEPROP 1 LAST CDS_LMAN_SYM_OUTLINE -25,50,25,-50
J 2
(3825 3150);
DISPLAY 0.468085 (3825 3150);
PAINT GREEN (3825 3150);
DISPLAY INVISIBLE (3825 3150);
FORCEPROP 2 LAST CDS_LIB pure_quanta
J 2
(3825 3150);
DISPLAY INVISIBLE (3825 3150);
FORCEPROP 1 LAST PIN_NAMES_ROTATE TRUE
J 2
(3825 3150);
DISPLAY 0.489362 (3825 3150);
PAINT GREEN (3825 3150);
DISPLAY INVISIBLE (3825 3150);
FORCEPROP 2 LAST VOLTAGE 6.3V
J 2
(3475 3200);
DISPLAY 0.553191 (3475 3200);
DISPLAY INVISIBLE (3475 3200);
FORCEPROP 1 LAST MATERIAL X6S
J 2
(3834 3229);
DISPLAY 0.574468 (3834 3229);
PAINT GREEN (3834 3229);
DISPLAY INVISIBLE (3834 3229);
FORCEPROP 2 LAST PACK_TYPE C0201
J 2
(3650 3200);
DISPLAY 0.553191 (3650 3200);
DISPLAY INVISIBLE (3650 3200);
FORCEPROP 2 LAST TOLERANCE 20%
J 2
(3750 3200);
DISPLAY 0.553191 (3750 3200);
DISPLAY INVISIBLE (3750 3200);
FORCEPROP 1 LAST PART_NUMBER SP_CH4221MEE01
J 2
(3709 3238);
DISPLAY 0.574468 (3709 3238);
PAINT GREEN (3709 3238);
DISPLAY INVISIBLE (3709 3238);
FORCEPROP 1 LAST LOCATION C874
J 0
(4075 3225);
DISPLAY 1.021277 (4075 3225);
DISPLAY INVISIBLE (4075 3225);
FORCEPROP 1 LAST PATH I165
J 2
(3825 3150);
DISPLAY 0.723404 (3825 3150);
DISPLAY INVISIBLE (3825 3150);
FORCEADD Q_CAP_DIFFBUS..2
R 2
(3825 3300);
FORCEPROP 1 LAST LOCATION C873
J 2
(4059 3317);
DISPLAY 0.723404 (4059 3317);
PAINT GREEN (4059 3317);
FORCEPROP 2 LAST $SEC 1
J 2
(4000 3375);
DISPLAY 0.680851 (4000 3375);
PAINT MONO (4000 3375);
DISPLAY INVISIBLE (4000 3375);
FORCEPROP 2 LAST CDS_SEC 1
J 2
(4000 3375);
DISPLAY 0.680851 (4000 3375);
DISPLAY INVISIBLE (4000 3375);
FORCEPROP 2 LASTPIN (3900 3300) $PN 1
J 0
(3910 3310);
DISPLAY 0.808511 (3910 3310);
FORCEPROP 2 LASTPIN (3750 3300) $PN 2
J 2
(3740 3310);
DISPLAY 0.808511 (3740 3310);
FORCEPROP 2 LAST VALUE DIFF BUS_0.22UF
J 2
(3675 3300);
DISPLAY 0.553191 (3675 3300);
FORCEPROP 1 LAST CDS_LMAN_SYM_OUTLINE -25,50,25,-50
J 2
(3825 3300);
DISPLAY 0.468085 (3825 3300);
PAINT GREEN (3825 3300);
DISPLAY INVISIBLE (3825 3300);
FORCEPROP 2 LAST CDS_LIB pure_quanta
J 2
(3825 3300);
DISPLAY INVISIBLE (3825 3300);
FORCEPROP 1 LAST PIN_NAMES_ROTATE TRUE
J 2
(3825 3300);
DISPLAY 0.489362 (3825 3300);
PAINT GREEN (3825 3300);
DISPLAY INVISIBLE (3825 3300);
FORCEPROP 2 LAST VOLTAGE 6.3V
J 2
(3475 3350);
DISPLAY 0.553191 (3475 3350);
DISPLAY INVISIBLE (3475 3350);
FORCEPROP 1 LAST MATERIAL X6S
J 2
(3834 3379);
DISPLAY 0.574468 (3834 3379);
PAINT GREEN (3834 3379);
DISPLAY INVISIBLE (3834 3379);
FORCEPROP 2 LAST PACK_TYPE C0201
J 2
(3650 3350);
DISPLAY 0.553191 (3650 3350);
DISPLAY INVISIBLE (3650 3350);
FORCEPROP 2 LAST TOLERANCE 20%
J 2
(3750 3350);
DISPLAY 0.553191 (3750 3350);
DISPLAY INVISIBLE (3750 3350);
FORCEPROP 1 LAST PART_NUMBER SP_CH4221MEE01
J 2
(3709 3388);
DISPLAY 0.574468 (3709 3388);
PAINT GREEN (3709 3388);
DISPLAY INVISIBLE (3709 3388);
FORCEPROP 1 LAST LOCATION C873
J 0
(4075 3375);
DISPLAY 1.021277 (4075 3375);
DISPLAY INVISIBLE (4075 3375);
FORCEPROP 1 LAST PATH I166
J 2
(3825 3300);
DISPLAY 0.723404 (3825 3300);
DISPLAY INVISIBLE (3825 3300);
FORCEADD Q_CAP_DIFFBUS..2
R 2
(3825 3350);
FORCEPROP 1 LAST LOCATION C872
J 2
(4059 3367);
DISPLAY 0.723404 (4059 3367);
PAINT GREEN (4059 3367);
FORCEPROP 2 LAST $SEC 1
J 2
(4000 3425);
DISPLAY 0.680851 (4000 3425);
PAINT MONO (4000 3425);
DISPLAY INVISIBLE (4000 3425);
FORCEPROP 2 LAST CDS_SEC 1
J 2
(4000 3425);
DISPLAY 0.680851 (4000 3425);
DISPLAY INVISIBLE (4000 3425);
FORCEPROP 2 LASTPIN (3900 3350) $PN 1
J 0
(3910 3360);
DISPLAY 0.808511 (3910 3360);
FORCEPROP 2 LASTPIN (3750 3350) $PN 2
J 2
(3740 3360);
DISPLAY 0.808511 (3740 3360);
FORCEPROP 2 LAST VALUE DIFF BUS_0.22UF
J 2
(3675 3350);
DISPLAY 0.553191 (3675 3350);
FORCEPROP 1 LAST CDS_LMAN_SYM_OUTLINE -25,50,25,-50
J 2
(3825 3350);
DISPLAY 0.468085 (3825 3350);
PAINT GREEN (3825 3350);
DISPLAY INVISIBLE (3825 3350);
FORCEPROP 2 LAST CDS_LIB pure_quanta
J 2
(3825 3350);
DISPLAY INVISIBLE (3825 3350);
FORCEPROP 1 LAST PIN_NAMES_ROTATE TRUE
J 2
(3825 3350);
DISPLAY 0.489362 (3825 3350);
PAINT GREEN (3825 3350);
DISPLAY INVISIBLE (3825 3350);
FORCEPROP 2 LAST VOLTAGE 6.3V
J 2
(3475 3400);
DISPLAY 0.553191 (3475 3400);
DISPLAY INVISIBLE (3475 3400);
FORCEPROP 1 LAST MATERIAL X6S
J 2
(3834 3429);
DISPLAY 0.574468 (3834 3429);
PAINT GREEN (3834 3429);
DISPLAY INVISIBLE (3834 3429);
FORCEPROP 2 LAST PACK_TYPE C0201
J 2
(3650 3400);
DISPLAY 0.553191 (3650 3400);
DISPLAY INVISIBLE (3650 3400);
FORCEPROP 2 LAST TOLERANCE 20%
J 2
(3750 3400);
DISPLAY 0.553191 (3750 3400);
DISPLAY INVISIBLE (3750 3400);
FORCEPROP 1 LAST PART_NUMBER SP_CH4221MEE01
J 2
(3709 3438);
DISPLAY 0.574468 (3709 3438);
PAINT GREEN (3709 3438);
DISPLAY INVISIBLE (3709 3438);
FORCEPROP 1 LAST LOCATION C872
J 0
(4075 3425);
DISPLAY 1.021277 (4075 3425);
DISPLAY INVISIBLE (4075 3425);
FORCEPROP 1 LAST PATH I167
J 2
(3825 3350);
DISPLAY 0.723404 (3825 3350);
DISPLAY INVISIBLE (3825 3350);
FORCEADD Q_CAP_DIFFBUS..2
R 2
(3825 3500);
FORCEPROP 1 LAST LOCATION C871
J 2
(4059 3517);
DISPLAY 0.723404 (4059 3517);
PAINT GREEN (4059 3517);
FORCEPROP 2 LAST $SEC 1
J 2
(4000 3575);
DISPLAY 0.680851 (4000 3575);
PAINT MONO (4000 3575);
DISPLAY INVISIBLE (4000 3575);
FORCEPROP 2 LAST CDS_SEC 1
J 2
(4000 3575);
DISPLAY 0.680851 (4000 3575);
DISPLAY INVISIBLE (4000 3575);
FORCEPROP 2 LASTPIN (3900 3500) $PN 1
J 0
(3910 3510);
DISPLAY 0.808511 (3910 3510);
FORCEPROP 2 LASTPIN (3750 3500) $PN 2
J 2
(3740 3510);
DISPLAY 0.808511 (3740 3510);
FORCEPROP 2 LAST VALUE DIFF BUS_0.22UF
J 2
(3675 3500);
DISPLAY 0.553191 (3675 3500);
FORCEPROP 1 LAST CDS_LMAN_SYM_OUTLINE -25,50,25,-50
J 2
(3825 3500);
DISPLAY 0.468085 (3825 3500);
PAINT GREEN (3825 3500);
DISPLAY INVISIBLE (3825 3500);
FORCEPROP 2 LAST CDS_LIB pure_quanta
J 2
(3825 3500);
DISPLAY INVISIBLE (3825 3500);
FORCEPROP 1 LAST PIN_NAMES_ROTATE TRUE
J 2
(3825 3500);
DISPLAY 0.489362 (3825 3500);
PAINT GREEN (3825 3500);
DISPLAY INVISIBLE (3825 3500);
FORCEPROP 2 LAST VOLTAGE 6.3V
J 2
(3475 3550);
DISPLAY 0.553191 (3475 3550);
DISPLAY INVISIBLE (3475 3550);
FORCEPROP 1 LAST MATERIAL X6S
J 2
(3834 3579);
DISPLAY 0.574468 (3834 3579);
PAINT GREEN (3834 3579);
DISPLAY INVISIBLE (3834 3579);
FORCEPROP 2 LAST PACK_TYPE C0201
J 2
(3650 3550);
DISPLAY 0.553191 (3650 3550);
DISPLAY INVISIBLE (3650 3550);
FORCEPROP 2 LAST TOLERANCE 20%
J 2
(3750 3550);
DISPLAY 0.553191 (3750 3550);
DISPLAY INVISIBLE (3750 3550);
FORCEPROP 1 LAST PART_NUMBER SP_CH4221MEE01
J 2
(3709 3588);
DISPLAY 0.574468 (3709 3588);
PAINT GREEN (3709 3588);
DISPLAY INVISIBLE (3709 3588);
FORCEPROP 1 LAST LOCATION C871
J 0
(4075 3575);
DISPLAY 1.021277 (4075 3575);
DISPLAY INVISIBLE (4075 3575);
FORCEPROP 1 LAST PATH I168
J 2
(3825 3500);
DISPLAY 0.723404 (3825 3500);
DISPLAY INVISIBLE (3825 3500);
FORCEADD Q_CAP_DIFFBUS..2
R 2
(3825 3550);
FORCEPROP 1 LAST LOCATION C870
J 2
(4059 3567);
DISPLAY 0.723404 (4059 3567);
PAINT GREEN (4059 3567);
FORCEPROP 2 LAST $SEC 1
J 2
(4000 3625);
DISPLAY 0.680851 (4000 3625);
PAINT MONO (4000 3625);
DISPLAY INVISIBLE (4000 3625);
FORCEPROP 2 LAST CDS_SEC 1
J 2
(4000 3625);
DISPLAY 0.680851 (4000 3625);
DISPLAY INVISIBLE (4000 3625);
FORCEPROP 2 LASTPIN (3900 3550) $PN 1
J 0
(3910 3560);
DISPLAY 0.808511 (3910 3560);
FORCEPROP 2 LASTPIN (3750 3550) $PN 2
J 2
(3740 3560);
DISPLAY 0.808511 (3740 3560);
FORCEPROP 1 LAST MATERIAL X6S
J 2
(3784 3754);
DISPLAY 0.574468 (3784 3754);
PAINT GREEN (3784 3754);
FORCEPROP 2 LAST VALUE DIFF BUS_0.22UF
J 2
(3675 3550);
DISPLAY 0.553191 (3675 3550);
FORCEPROP 2 LAST VOLTAGE 6.3V
J 2
(4075 3700);
DISPLAY 0.553191 (4075 3700);
PAINT GREEN (4075 3700);
FORCEPROP 2 LAST TOLERANCE 20%
J 2
(3925 3700);
DISPLAY 0.553191 (3925 3700);
PAINT GREEN (3925 3700);
FORCEPROP 2 LAST PACK_TYPE C0201
J 2
(3825 3700);
DISPLAY 0.553191 (3825 3700);
PAINT GREEN (3825 3700);
FORCEPROP 2 LAST CDS_LIB pure_quanta
J 2
(3825 3550);
DISPLAY INVISIBLE (3825 3550);
FORCEPROP 1 LAST CDS_LMAN_SYM_OUTLINE -25,50,25,-50
J 2
(3825 3550);
DISPLAY 0.468085 (3825 3550);
PAINT GREEN (3825 3550);
DISPLAY INVISIBLE (3825 3550);
FORCEPROP 1 LAST PIN_NAMES_ROTATE TRUE
J 2
(3825 3550);
DISPLAY 0.489362 (3825 3550);
PAINT GREEN (3825 3550);
DISPLAY INVISIBLE (3825 3550);
FORCEPROP 1 LAST PART_NUMBER SP_CH4221MEE01
J 2
(4084 3638);
DISPLAY 0.574468 (4084 3638);
PAINT GREEN (4084 3638);
DISPLAY INVISIBLE (4084 3638);
FORCEPROP 1 LAST LOCATION C870
J 0
(4075 3625);
DISPLAY 1.021277 (4075 3625);
DISPLAY INVISIBLE (4075 3625);
FORCEPROP 1 LAST PATH I169
J 2
(3825 3550);
DISPLAY 0.723404 (3825 3550);
DISPLAY INVISIBLE (3825 3550);
FORCEADD TAP..1
R 2
(-1625 1525);
FORCEPROP 3 LASTPIN (-1575 1525) SIG_NAME P5E_CPU0_P2_TX_DP<7>
J 0
(-1565 1535);
DISPLAY 0.659574 (-1565 1535);
PAINT MONO (-1565 1535);
DISPLAY INVISIBLE (-1565 1535);
FORCEPROP 1 LASTPIN (-1575 1525) BN 7
J 2
(-1563 1533);
DISPLAY 0.680851 (-1563 1533);
PAINT GREEN (-1563 1533);
FORCEPROP 2 LAST CDS_LIB standard
J 0
(-1625 1525);
DISPLAY INVISIBLE (-1625 1525);
FORCEPROP 1 LAST BODY_TYPE PLUMBING
J 2
(-1625 1575);
DISPLAY 0.872340 (-1625 1575);
PAINT GREEN (-1625 1575);
DISPLAY INVISIBLE (-1625 1575);
FORCEPROP 1 LAST HDL_TAP TRUE
J 2
(-1950 1400);
DISPLAY 0.872340 (-1950 1400);
DISPLAY INVISIBLE (-1950 1400);
FORCEPROP 1 LAST PATH I17
J 2
(-1623 1525);
DISPLAY 0.872340 (-1623 1525);
PAINT GREEN (-1623 1525);
DISPLAY INVISIBLE (-1623 1525);
FORCEADD TAP..1
(4375 175);
FORCEPROP 3 LASTPIN (4325 175) SIG_NAME P5E_CPU0_P3_TX_C_DN<0>
J 0
(4335 185);
DISPLAY 0.659574 (4335 185);
PAINT MONO (4335 185);
DISPLAY INVISIBLE (4335 185);
FORCEPROP 1 LASTPIN (4325 175) BN 0
J 0
(4313 183);
DISPLAY 0.680851 (4313 183);
PAINT GREEN (4313 183);
FORCEPROP 2 LAST CDS_LIB standard
J 0
(4375 175);
DISPLAY INVISIBLE (4375 175);
FORCEPROP 1 LAST BODY_TYPE PLUMBING
J 0
(4375 225);
DISPLAY 0.872340 (4375 225);
PAINT GREEN (4375 225);
DISPLAY INVISIBLE (4375 225);
FORCEPROP 1 LAST HDL_TAP TRUE
J 0
(4700 50);
DISPLAY 0.872340 (4700 50);
DISPLAY INVISIBLE (4700 50);
FORCEPROP 1 LAST PATH I170
J 0
(4373 175);
DISPLAY 0.872340 (4373 175);
PAINT GREEN (4373 175);
DISPLAY INVISIBLE (4373 175);
FORCEADD TAP..1
(4375 375);
FORCEPROP 3 LASTPIN (4325 375) SIG_NAME P5E_CPU0_P3_TX_C_DN<1>
J 0
(4335 385);
DISPLAY 0.659574 (4335 385);
PAINT MONO (4335 385);
DISPLAY INVISIBLE (4335 385);
FORCEPROP 1 LASTPIN (4325 375) BN 1
J 0
(4313 383);
DISPLAY 0.680851 (4313 383);
PAINT GREEN (4313 383);
FORCEPROP 2 LAST CDS_LIB standard
J 0
(4375 375);
DISPLAY INVISIBLE (4375 375);
FORCEPROP 1 LAST BODY_TYPE PLUMBING
J 0
(4375 425);
DISPLAY 0.872340 (4375 425);
PAINT GREEN (4375 425);
DISPLAY INVISIBLE (4375 425);
FORCEPROP 1 LAST HDL_TAP TRUE
J 0
(4700 250);
DISPLAY 0.872340 (4700 250);
DISPLAY INVISIBLE (4700 250);
FORCEPROP 1 LAST PATH I171
J 0
(4373 375);
DISPLAY 0.872340 (4373 375);
PAINT GREEN (4373 375);
DISPLAY INVISIBLE (4373 375);
FORCEADD TAP..1
(4375 575);
FORCEPROP 3 LASTPIN (4325 575) SIG_NAME P5E_CPU0_P3_TX_C_DN<2>
J 0
(4335 585);
DISPLAY 0.659574 (4335 585);
PAINT MONO (4335 585);
DISPLAY INVISIBLE (4335 585);
FORCEPROP 1 LASTPIN (4325 575) BN 2
J 0
(4313 583);
DISPLAY 0.680851 (4313 583);
PAINT GREEN (4313 583);
FORCEPROP 2 LAST CDS_LIB standard
J 0
(4375 575);
DISPLAY INVISIBLE (4375 575);
FORCEPROP 1 LAST BODY_TYPE PLUMBING
J 0
(4375 625);
DISPLAY 0.872340 (4375 625);
PAINT GREEN (4375 625);
DISPLAY INVISIBLE (4375 625);
FORCEPROP 1 LAST HDL_TAP TRUE
J 0
(4700 450);
DISPLAY 0.872340 (4700 450);
DISPLAY INVISIBLE (4700 450);
FORCEPROP 1 LAST PATH I172
J 0
(4373 575);
DISPLAY 0.872340 (4373 575);
PAINT GREEN (4373 575);
DISPLAY INVISIBLE (4373 575);
FORCEADD TAP..1
(4375 975);
FORCEPROP 3 LASTPIN (4325 975) SIG_NAME P5E_CPU0_P3_TX_C_DN<4>
J 0
(4335 985);
DISPLAY 0.659574 (4335 985);
PAINT MONO (4335 985);
DISPLAY INVISIBLE (4335 985);
FORCEPROP 1 LASTPIN (4325 975) BN 4
J 0
(4313 983);
DISPLAY 0.680851 (4313 983);
PAINT GREEN (4313 983);
FORCEPROP 2 LAST CDS_LIB standard
J 0
(4375 975);
DISPLAY INVISIBLE (4375 975);
FORCEPROP 1 LAST BODY_TYPE PLUMBING
J 0
(4375 1025);
DISPLAY 0.872340 (4375 1025);
PAINT GREEN (4375 1025);
DISPLAY INVISIBLE (4375 1025);
FORCEPROP 1 LAST HDL_TAP TRUE
J 0
(4700 850);
DISPLAY 0.872340 (4700 850);
DISPLAY INVISIBLE (4700 850);
FORCEPROP 1 LAST PATH I173
J 0
(4373 975);
DISPLAY 0.872340 (4373 975);
PAINT GREEN (4373 975);
DISPLAY INVISIBLE (4373 975);
FORCEADD TAP..1
(4375 775);
FORCEPROP 3 LASTPIN (4325 775) SIG_NAME P5E_CPU0_P3_TX_C_DN<3>
J 0
(4335 785);
DISPLAY 0.659574 (4335 785);
PAINT MONO (4335 785);
DISPLAY INVISIBLE (4335 785);
FORCEPROP 1 LASTPIN (4325 775) BN 3
J 0
(4313 783);
DISPLAY 0.680851 (4313 783);
PAINT GREEN (4313 783);
FORCEPROP 2 LAST CDS_LIB standard
J 0
(4375 775);
DISPLAY INVISIBLE (4375 775);
FORCEPROP 1 LAST BODY_TYPE PLUMBING
J 0
(4375 825);
DISPLAY 0.872340 (4375 825);
PAINT GREEN (4375 825);
DISPLAY INVISIBLE (4375 825);
FORCEPROP 1 LAST HDL_TAP TRUE
J 0
(4700 650);
DISPLAY 0.872340 (4700 650);
DISPLAY INVISIBLE (4700 650);
FORCEPROP 1 LAST PATH I174
J 0
(4373 775);
DISPLAY 0.872340 (4373 775);
PAINT GREEN (4373 775);
DISPLAY INVISIBLE (4373 775);
FORCEADD TAP..1
(4575 125);
FORCEPROP 3 LASTPIN (4525 125) SIG_NAME P5E_CPU0_P3_TX_C_DP<0>
J 0
(4535 135);
DISPLAY 0.659574 (4535 135);
PAINT MONO (4535 135);
DISPLAY INVISIBLE (4535 135);
FORCEPROP 1 LASTPIN (4525 125) BN 0
J 0
(4513 133);
DISPLAY 0.680851 (4513 133);
PAINT GREEN (4513 133);
FORCEPROP 2 LAST CDS_LIB standard
J 0
(4575 125);
DISPLAY INVISIBLE (4575 125);
FORCEPROP 1 LAST BODY_TYPE PLUMBING
J 0
(4575 175);
DISPLAY 0.872340 (4575 175);
PAINT GREEN (4575 175);
DISPLAY INVISIBLE (4575 175);
FORCEPROP 1 LAST HDL_TAP TRUE
J 0
(4900 0);
DISPLAY 0.872340 (4900 0);
DISPLAY INVISIBLE (4900 0);
FORCEPROP 1 LAST PATH I175
J 0
(4573 125);
DISPLAY 0.872340 (4573 125);
PAINT GREEN (4573 125);
DISPLAY INVISIBLE (4573 125);
FORCEADD TAP..1
(4575 325);
FORCEPROP 3 LASTPIN (4525 325) SIG_NAME P5E_CPU0_P3_TX_C_DP<1>
J 0
(4535 335);
DISPLAY 0.659574 (4535 335);
PAINT MONO (4535 335);
DISPLAY INVISIBLE (4535 335);
FORCEPROP 1 LASTPIN (4525 325) BN 1
J 0
(4513 333);
DISPLAY 0.680851 (4513 333);
PAINT GREEN (4513 333);
FORCEPROP 2 LAST CDS_LIB standard
J 0
(4575 325);
DISPLAY INVISIBLE (4575 325);
FORCEPROP 1 LAST BODY_TYPE PLUMBING
J 0
(4575 375);
DISPLAY 0.872340 (4575 375);
PAINT GREEN (4575 375);
DISPLAY INVISIBLE (4575 375);
FORCEPROP 1 LAST HDL_TAP TRUE
J 0
(4900 200);
DISPLAY 0.872340 (4900 200);
DISPLAY INVISIBLE (4900 200);
FORCEPROP 1 LAST PATH I176
J 0
(4573 325);
DISPLAY 0.872340 (4573 325);
PAINT GREEN (4573 325);
DISPLAY INVISIBLE (4573 325);
FORCEADD TAP..1
(4575 525);
FORCEPROP 3 LASTPIN (4525 525) SIG_NAME P5E_CPU0_P3_TX_C_DP<2>
J 0
(4535 535);
DISPLAY 0.659574 (4535 535);
PAINT MONO (4535 535);
DISPLAY INVISIBLE (4535 535);
FORCEPROP 1 LASTPIN (4525 525) BN 2
J 0
(4513 533);
DISPLAY 0.680851 (4513 533);
PAINT GREEN (4513 533);
FORCEPROP 2 LAST CDS_LIB standard
J 0
(4575 525);
DISPLAY INVISIBLE (4575 525);
FORCEPROP 1 LAST BODY_TYPE PLUMBING
J 0
(4575 575);
DISPLAY 0.872340 (4575 575);
PAINT GREEN (4575 575);
DISPLAY INVISIBLE (4575 575);
FORCEPROP 1 LAST HDL_TAP TRUE
J 0
(4900 400);
DISPLAY 0.872340 (4900 400);
DISPLAY INVISIBLE (4900 400);
FORCEPROP 1 LAST PATH I177
J 0
(4573 525);
DISPLAY 0.872340 (4573 525);
PAINT GREEN (4573 525);
DISPLAY INVISIBLE (4573 525);
FORCEADD TAP..1
(4575 725);
FORCEPROP 3 LASTPIN (4525 725) SIG_NAME P5E_CPU0_P3_TX_C_DP<3>
J 0
(4535 735);
DISPLAY 0.659574 (4535 735);
PAINT MONO (4535 735);
DISPLAY INVISIBLE (4535 735);
FORCEPROP 1 LASTPIN (4525 725) BN 3
J 0
(4513 733);
DISPLAY 0.680851 (4513 733);
PAINT GREEN (4513 733);
FORCEPROP 2 LAST CDS_LIB standard
J 0
(4575 725);
DISPLAY INVISIBLE (4575 725);
FORCEPROP 1 LAST BODY_TYPE PLUMBING
J 0
(4575 775);
DISPLAY 0.872340 (4575 775);
PAINT GREEN (4575 775);
DISPLAY INVISIBLE (4575 775);
FORCEPROP 1 LAST HDL_TAP TRUE
J 0
(4900 600);
DISPLAY 0.872340 (4900 600);
DISPLAY INVISIBLE (4900 600);
FORCEPROP 1 LAST PATH I178
J 0
(4573 725);
DISPLAY 0.872340 (4573 725);
PAINT GREEN (4573 725);
DISPLAY INVISIBLE (4573 725);
FORCEADD TAP..1
(4575 925);
FORCEPROP 3 LASTPIN (4525 925) SIG_NAME P5E_CPU0_P3_TX_C_DP<4>
J 0
(4535 935);
DISPLAY 0.659574 (4535 935);
PAINT MONO (4535 935);
DISPLAY INVISIBLE (4535 935);
FORCEPROP 1 LASTPIN (4525 925) BN 4
J 0
(4513 933);
DISPLAY 0.680851 (4513 933);
PAINT GREEN (4513 933);
FORCEPROP 2 LAST CDS_LIB standard
J 0
(4575 925);
DISPLAY INVISIBLE (4575 925);
FORCEPROP 1 LAST BODY_TYPE PLUMBING
J 0
(4575 975);
DISPLAY 0.872340 (4575 975);
PAINT GREEN (4575 975);
DISPLAY INVISIBLE (4575 975);
FORCEPROP 1 LAST HDL_TAP TRUE
J 0
(4900 800);
DISPLAY 0.872340 (4900 800);
DISPLAY INVISIBLE (4900 800);
FORCEPROP 1 LAST PATH I179
J 0
(4573 925);
DISPLAY 0.872340 (4573 925);
PAINT GREEN (4573 925);
DISPLAY INVISIBLE (4573 925);
FORCEADD TAP..1
R 2
(-1375 1175);
FORCEPROP 3 LASTPIN (-1325 1175) SIG_NAME P5E_CPU0_P2_TX_DN<5>
J 0
(-1315 1185);
DISPLAY 0.659574 (-1315 1185);
PAINT MONO (-1315 1185);
DISPLAY INVISIBLE (-1315 1185);
FORCEPROP 1 LASTPIN (-1325 1175) BN 5
J 2
(-1313 1183);
DISPLAY 0.680851 (-1313 1183);
PAINT GREEN (-1313 1183);
FORCEPROP 2 LAST CDS_LIB standard
J 0
(-1375 1175);
DISPLAY INVISIBLE (-1375 1175);
FORCEPROP 1 LAST BODY_TYPE PLUMBING
J 2
(-1375 1225);
DISPLAY 0.872340 (-1375 1225);
PAINT GREEN (-1375 1225);
DISPLAY INVISIBLE (-1375 1225);
FORCEPROP 1 LAST HDL_TAP TRUE
J 2
(-1700 1050);
DISPLAY 0.872340 (-1700 1050);
DISPLAY INVISIBLE (-1700 1050);
FORCEPROP 1 LAST PATH I18
J 2
(-1373 1175);
DISPLAY 0.872340 (-1373 1175);
PAINT GREEN (-1373 1175);
DISPLAY INVISIBLE (-1373 1175);
FORCEADD TAP..1
(4375 1175);
FORCEPROP 3 LASTPIN (4325 1175) SIG_NAME P5E_CPU0_P3_TX_C_DN<5>
J 0
(4335 1185);
DISPLAY 0.659574 (4335 1185);
PAINT MONO (4335 1185);
DISPLAY INVISIBLE (4335 1185);
FORCEPROP 1 LASTPIN (4325 1175) BN 5
J 0
(4313 1183);
DISPLAY 0.680851 (4313 1183);
PAINT GREEN (4313 1183);
FORCEPROP 2 LAST CDS_LIB standard
J 0
(4375 1175);
DISPLAY INVISIBLE (4375 1175);
FORCEPROP 1 LAST BODY_TYPE PLUMBING
J 0
(4375 1225);
DISPLAY 0.872340 (4375 1225);
PAINT GREEN (4375 1225);
DISPLAY INVISIBLE (4375 1225);
FORCEPROP 1 LAST HDL_TAP TRUE
J 0
(4700 1050);
DISPLAY 0.872340 (4700 1050);
DISPLAY INVISIBLE (4700 1050);
FORCEPROP 1 LAST PATH I180
J 0
(4373 1175);
DISPLAY 0.872340 (4373 1175);
PAINT GREEN (4373 1175);
DISPLAY INVISIBLE (4373 1175);
FORCEADD TAP..1
(4375 1375);
FORCEPROP 3 LASTPIN (4325 1375) SIG_NAME P5E_CPU0_P3_TX_C_DN<6>
J 0
(4335 1385);
DISPLAY 0.659574 (4335 1385);
PAINT MONO (4335 1385);
DISPLAY INVISIBLE (4335 1385);
FORCEPROP 1 LASTPIN (4325 1375) BN 6
J 0
(4313 1383);
DISPLAY 0.680851 (4313 1383);
PAINT GREEN (4313 1383);
FORCEPROP 2 LAST CDS_LIB standard
J 0
(4375 1375);
DISPLAY INVISIBLE (4375 1375);
FORCEPROP 1 LAST BODY_TYPE PLUMBING
J 0
(4375 1425);
DISPLAY 0.872340 (4375 1425);
PAINT GREEN (4375 1425);
DISPLAY INVISIBLE (4375 1425);
FORCEPROP 1 LAST HDL_TAP TRUE
J 0
(4700 1250);
DISPLAY 0.872340 (4700 1250);
DISPLAY INVISIBLE (4700 1250);
FORCEPROP 1 LAST PATH I181
J 0
(4373 1375);
DISPLAY 0.872340 (4373 1375);
PAINT GREEN (4373 1375);
DISPLAY INVISIBLE (4373 1375);
FORCEADD TAP..1
(4375 1575);
FORCEPROP 3 LASTPIN (4325 1575) SIG_NAME P5E_CPU0_P3_TX_C_DN<7>
J 0
(4335 1585);
DISPLAY 0.659574 (4335 1585);
PAINT MONO (4335 1585);
DISPLAY INVISIBLE (4335 1585);
FORCEPROP 1 LASTPIN (4325 1575) BN 7
J 0
(4313 1583);
DISPLAY 0.680851 (4313 1583);
PAINT GREEN (4313 1583);
FORCEPROP 2 LAST CDS_LIB standard
J 0
(4375 1575);
DISPLAY INVISIBLE (4375 1575);
FORCEPROP 1 LAST BODY_TYPE PLUMBING
J 0
(4375 1625);
DISPLAY 0.872340 (4375 1625);
PAINT GREEN (4375 1625);
DISPLAY INVISIBLE (4375 1625);
FORCEPROP 1 LAST HDL_TAP TRUE
J 0
(4700 1450);
DISPLAY 0.872340 (4700 1450);
DISPLAY INVISIBLE (4700 1450);
FORCEPROP 1 LAST PATH I182
J 0
(4373 1575);
DISPLAY 0.872340 (4373 1575);
PAINT GREEN (4373 1575);
DISPLAY INVISIBLE (4373 1575);
FORCEADD TAP..1
(4575 1125);
FORCEPROP 3 LASTPIN (4525 1125) SIG_NAME P5E_CPU0_P3_TX_C_DP<5>
J 0
(4535 1135);
DISPLAY 0.659574 (4535 1135);
PAINT MONO (4535 1135);
DISPLAY INVISIBLE (4535 1135);
FORCEPROP 1 LASTPIN (4525 1125) BN 5
J 0
(4513 1133);
DISPLAY 0.680851 (4513 1133);
PAINT GREEN (4513 1133);
FORCEPROP 2 LAST CDS_LIB standard
J 0
(4575 1125);
DISPLAY INVISIBLE (4575 1125);
FORCEPROP 1 LAST BODY_TYPE PLUMBING
J 0
(4575 1175);
DISPLAY 0.872340 (4575 1175);
PAINT GREEN (4575 1175);
DISPLAY INVISIBLE (4575 1175);
FORCEPROP 1 LAST HDL_TAP TRUE
J 0
(4900 1000);
DISPLAY 0.872340 (4900 1000);
DISPLAY INVISIBLE (4900 1000);
FORCEPROP 1 LAST PATH I183
J 0
(4573 1125);
DISPLAY 0.872340 (4573 1125);
PAINT GREEN (4573 1125);
DISPLAY INVISIBLE (4573 1125);
FORCEADD TAP..1
(4575 1325);
FORCEPROP 3 LASTPIN (4525 1325) SIG_NAME P5E_CPU0_P3_TX_C_DP<6>
J 0
(4535 1335);
DISPLAY 0.659574 (4535 1335);
PAINT MONO (4535 1335);
DISPLAY INVISIBLE (4535 1335);
FORCEPROP 1 LASTPIN (4525 1325) BN 6
J 0
(4513 1333);
DISPLAY 0.680851 (4513 1333);
PAINT GREEN (4513 1333);
FORCEPROP 2 LAST CDS_LIB standard
J 0
(4575 1325);
DISPLAY INVISIBLE (4575 1325);
FORCEPROP 1 LAST BODY_TYPE PLUMBING
J 0
(4575 1375);
DISPLAY 0.872340 (4575 1375);
PAINT GREEN (4575 1375);
DISPLAY INVISIBLE (4575 1375);
FORCEPROP 1 LAST HDL_TAP TRUE
J 0
(4900 1200);
DISPLAY 0.872340 (4900 1200);
DISPLAY INVISIBLE (4900 1200);
FORCEPROP 1 LAST PATH I184
J 0
(4573 1325);
DISPLAY 0.872340 (4573 1325);
PAINT GREEN (4573 1325);
DISPLAY INVISIBLE (4573 1325);
FORCEADD TAP..1
(4575 1525);
FORCEPROP 3 LASTPIN (4525 1525) SIG_NAME P5E_CPU0_P3_TX_C_DP<7>
J 0
(4535 1535);
DISPLAY 0.659574 (4535 1535);
PAINT MONO (4535 1535);
DISPLAY INVISIBLE (4535 1535);
FORCEPROP 1 LASTPIN (4525 1525) BN 7
J 0
(4513 1533);
DISPLAY 0.680851 (4513 1533);
PAINT GREEN (4513 1533);
FORCEPROP 2 LAST CDS_LIB standard
J 0
(4575 1525);
DISPLAY INVISIBLE (4575 1525);
FORCEPROP 1 LAST BODY_TYPE PLUMBING
J 0
(4575 1575);
DISPLAY 0.872340 (4575 1575);
PAINT GREEN (4575 1575);
DISPLAY INVISIBLE (4575 1575);
FORCEPROP 1 LAST HDL_TAP TRUE
J 0
(4900 1400);
DISPLAY 0.872340 (4900 1400);
DISPLAY INVISIBLE (4900 1400);
FORCEPROP 1 LAST PATH I185
J 0
(4573 1525);
DISPLAY 0.872340 (4573 1525);
PAINT GREEN (4573 1525);
DISPLAY INVISIBLE (4573 1525);
FORCEADD OFFPAGE..2
(5575 1550);
FORCEPROP 2 LAST $XR0 306 
J 0
(5764 1550);
DISPLAY 0.638298 (5764 1550);
PAINT MONO (5764 1550);
FORCEPROP 2 LAST CDS_LIB standard
J 0
(5575 1550);
DISPLAY INVISIBLE (5575 1550);
FORCEPROP 1 LAST OFFPAGE TRUE
J 0
(5900 1425);
DISPLAY 0.872340 (5900 1425);
DISPLAY INVISIBLE (5900 1425);
FORCEPROP 1 LAST COMMENT_BODY TRUE
J 0
(5530 1455);
DISPLAY 0.872340 (5530 1455);
PAINT GREEN (5530 1455);
DISPLAY INVISIBLE (5530 1455);
FORCEPROP 2 LAST PATH I186
J 0
(5775 1600);
DISPLAY 1.021277 (5775 1600);
DISPLAY INVISIBLE (5775 1600);
FORCEADD OFFPAGE..2
(5575 1600);
FORCEPROP 2 LAST $XR0 306 
J 0
(5764 1600);
DISPLAY 0.638298 (5764 1600);
PAINT MONO (5764 1600);
FORCEPROP 2 LAST CDS_LIB standard
J 0
(5575 1600);
DISPLAY INVISIBLE (5575 1600);
FORCEPROP 1 LAST OFFPAGE TRUE
J 0
(5900 1475);
DISPLAY 0.872340 (5900 1475);
DISPLAY INVISIBLE (5900 1475);
FORCEPROP 1 LAST COMMENT_BODY TRUE
J 0
(5530 1505);
DISPLAY 0.872340 (5530 1505);
PAINT GREEN (5530 1505);
DISPLAY INVISIBLE (5530 1505);
FORCEPROP 2 LAST PATH I187
J 0
(5775 1650);
DISPLAY 1.021277 (5775 1650);
DISPLAY INVISIBLE (5775 1650);
FORCEADD TAP..1
(4375 2150);
FORCEPROP 3 LASTPIN (4325 2150) SIG_NAME P5E_CPU0_P3_TX_C_DN<8>
J 0
(4335 2160);
DISPLAY 0.659574 (4335 2160);
PAINT MONO (4335 2160);
DISPLAY INVISIBLE (4335 2160);
FORCEPROP 1 LASTPIN (4325 2150) BN 8
J 0
(4313 2158);
DISPLAY 0.680851 (4313 2158);
PAINT GREEN (4313 2158);
FORCEPROP 2 LAST CDS_LIB standard
J 0
(4375 2150);
DISPLAY INVISIBLE (4375 2150);
FORCEPROP 1 LAST BODY_TYPE PLUMBING
J 0
(4375 2200);
DISPLAY 0.872340 (4375 2200);
PAINT GREEN (4375 2200);
DISPLAY INVISIBLE (4375 2200);
FORCEPROP 1 LAST HDL_TAP TRUE
J 0
(4700 2025);
DISPLAY 0.872340 (4700 2025);
DISPLAY INVISIBLE (4700 2025);
FORCEPROP 1 LAST PATH I188
J 0
(4373 2150);
DISPLAY 0.872340 (4373 2150);
PAINT GREEN (4373 2150);
DISPLAY INVISIBLE (4373 2150);
FORCEADD TAP..1
(4375 2350);
FORCEPROP 3 LASTPIN (4325 2350) SIG_NAME P5E_CPU0_P3_TX_C_DN<9>
J 0
(4335 2360);
DISPLAY 0.659574 (4335 2360);
PAINT MONO (4335 2360);
DISPLAY INVISIBLE (4335 2360);
FORCEPROP 1 LASTPIN (4325 2350) BN 9
J 0
(4313 2358);
DISPLAY 0.680851 (4313 2358);
PAINT GREEN (4313 2358);
FORCEPROP 2 LAST CDS_LIB standard
J 0
(4375 2350);
DISPLAY INVISIBLE (4375 2350);
FORCEPROP 1 LAST BODY_TYPE PLUMBING
J 0
(4375 2400);
DISPLAY 0.872340 (4375 2400);
PAINT GREEN (4375 2400);
DISPLAY INVISIBLE (4375 2400);
FORCEPROP 1 LAST HDL_TAP TRUE
J 0
(4700 2225);
DISPLAY 0.872340 (4700 2225);
DISPLAY INVISIBLE (4700 2225);
FORCEPROP 1 LAST PATH I189
J 0
(4373 2350);
DISPLAY 0.872340 (4373 2350);
PAINT GREEN (4373 2350);
DISPLAY INVISIBLE (4373 2350);
FORCEADD TAP..1
R 2
(-1375 1375);
FORCEPROP 3 LASTPIN (-1325 1375) SIG_NAME P5E_CPU0_P2_TX_DN<6>
J 0
(-1315 1385);
DISPLAY 0.659574 (-1315 1385);
PAINT MONO (-1315 1385);
DISPLAY INVISIBLE (-1315 1385);
FORCEPROP 1 LASTPIN (-1325 1375) BN 6
J 2
(-1313 1383);
DISPLAY 0.680851 (-1313 1383);
PAINT GREEN (-1313 1383);
FORCEPROP 2 LAST CDS_LIB standard
J 0
(-1375 1375);
DISPLAY INVISIBLE (-1375 1375);
FORCEPROP 1 LAST BODY_TYPE PLUMBING
J 2
(-1375 1425);
DISPLAY 0.872340 (-1375 1425);
PAINT GREEN (-1375 1425);
DISPLAY INVISIBLE (-1375 1425);
FORCEPROP 1 LAST HDL_TAP TRUE
J 2
(-1700 1250);
DISPLAY 0.872340 (-1700 1250);
DISPLAY INVISIBLE (-1700 1250);
FORCEPROP 1 LAST PATH I19
J 2
(-1373 1375);
DISPLAY 0.872340 (-1373 1375);
PAINT GREEN (-1373 1375);
DISPLAY INVISIBLE (-1373 1375);
FORCEADD TAP..1
(4375 2550);
FORCEPROP 3 LASTPIN (4325 2550) SIG_NAME P5E_CPU0_P3_TX_C_DN<10>
J 0
(4335 2560);
DISPLAY 0.659574 (4335 2560);
PAINT MONO (4335 2560);
DISPLAY INVISIBLE (4335 2560);
FORCEPROP 1 LASTPIN (4325 2550) BN 10
J 0
(4313 2558);
DISPLAY 0.680851 (4313 2558);
PAINT GREEN (4313 2558);
FORCEPROP 2 LAST CDS_LIB standard
J 0
(4375 2550);
DISPLAY INVISIBLE (4375 2550);
FORCEPROP 1 LAST BODY_TYPE PLUMBING
J 0
(4375 2600);
DISPLAY 0.872340 (4375 2600);
PAINT GREEN (4375 2600);
DISPLAY INVISIBLE (4375 2600);
FORCEPROP 1 LAST HDL_TAP TRUE
J 0
(4700 2425);
DISPLAY 0.872340 (4700 2425);
DISPLAY INVISIBLE (4700 2425);
FORCEPROP 1 LAST PATH I190
J 0
(4373 2550);
DISPLAY 0.872340 (4373 2550);
PAINT GREEN (4373 2550);
DISPLAY INVISIBLE (4373 2550);
FORCEADD TAP..1
(4375 2750);
FORCEPROP 3 LASTPIN (4325 2750) SIG_NAME P5E_CPU0_P3_TX_C_DN<11>
J 0
(4335 2760);
DISPLAY 0.659574 (4335 2760);
PAINT MONO (4335 2760);
DISPLAY INVISIBLE (4335 2760);
FORCEPROP 1 LASTPIN (4325 2750) BN 11
J 0
(4313 2758);
DISPLAY 0.680851 (4313 2758);
PAINT GREEN (4313 2758);
FORCEPROP 2 LAST CDS_LIB standard
J 0
(4375 2750);
DISPLAY INVISIBLE (4375 2750);
FORCEPROP 1 LAST BODY_TYPE PLUMBING
J 0
(4375 2800);
DISPLAY 0.872340 (4375 2800);
PAINT GREEN (4375 2800);
DISPLAY INVISIBLE (4375 2800);
FORCEPROP 1 LAST HDL_TAP TRUE
J 0
(4700 2625);
DISPLAY 0.872340 (4700 2625);
DISPLAY INVISIBLE (4700 2625);
FORCEPROP 1 LAST PATH I191
J 0
(4373 2750);
DISPLAY 0.872340 (4373 2750);
PAINT GREEN (4373 2750);
DISPLAY INVISIBLE (4373 2750);
FORCEADD TAP..1
(4375 2950);
FORCEPROP 3 LASTPIN (4325 2950) SIG_NAME P5E_CPU0_P3_TX_C_DN<12>
J 0
(4335 2960);
DISPLAY 0.659574 (4335 2960);
PAINT MONO (4335 2960);
DISPLAY INVISIBLE (4335 2960);
FORCEPROP 1 LASTPIN (4325 2950) BN 12
J 0
(4313 2958);
DISPLAY 0.680851 (4313 2958);
PAINT GREEN (4313 2958);
FORCEPROP 2 LAST CDS_LIB standard
J 0
(4375 2950);
DISPLAY INVISIBLE (4375 2950);
FORCEPROP 1 LAST BODY_TYPE PLUMBING
J 0
(4375 3000);
DISPLAY 0.872340 (4375 3000);
PAINT GREEN (4375 3000);
DISPLAY INVISIBLE (4375 3000);
FORCEPROP 1 LAST HDL_TAP TRUE
J 0
(4700 2825);
DISPLAY 0.872340 (4700 2825);
DISPLAY INVISIBLE (4700 2825);
FORCEPROP 1 LAST PATH I192
J 0
(4373 2950);
DISPLAY 0.872340 (4373 2950);
PAINT GREEN (4373 2950);
DISPLAY INVISIBLE (4373 2950);
FORCEADD TAP..1
(4575 2100);
FORCEPROP 3 LASTPIN (4525 2100) SIG_NAME P5E_CPU0_P3_TX_C_DP<8>
J 0
(4535 2110);
DISPLAY 0.659574 (4535 2110);
PAINT MONO (4535 2110);
DISPLAY INVISIBLE (4535 2110);
FORCEPROP 1 LASTPIN (4525 2100) BN 8
J 0
(4513 2108);
DISPLAY 0.680851 (4513 2108);
PAINT GREEN (4513 2108);
FORCEPROP 2 LAST CDS_LIB standard
J 0
(4575 2100);
DISPLAY INVISIBLE (4575 2100);
FORCEPROP 1 LAST BODY_TYPE PLUMBING
J 0
(4575 2150);
DISPLAY 0.872340 (4575 2150);
PAINT GREEN (4575 2150);
DISPLAY INVISIBLE (4575 2150);
FORCEPROP 1 LAST HDL_TAP TRUE
J 0
(4900 1975);
DISPLAY 0.872340 (4900 1975);
DISPLAY INVISIBLE (4900 1975);
FORCEPROP 1 LAST PATH I193
J 0
(4573 2100);
DISPLAY 0.872340 (4573 2100);
PAINT GREEN (4573 2100);
DISPLAY INVISIBLE (4573 2100);
FORCEADD TAP..1
(4575 2300);
FORCEPROP 3 LASTPIN (4525 2300) SIG_NAME P5E_CPU0_P3_TX_C_DP<9>
J 0
(4535 2310);
DISPLAY 0.659574 (4535 2310);
PAINT MONO (4535 2310);
DISPLAY INVISIBLE (4535 2310);
FORCEPROP 1 LASTPIN (4525 2300) BN 9
J 0
(4513 2308);
DISPLAY 0.680851 (4513 2308);
PAINT GREEN (4513 2308);
FORCEPROP 2 LAST CDS_LIB standard
J 0
(4575 2300);
DISPLAY INVISIBLE (4575 2300);
FORCEPROP 1 LAST BODY_TYPE PLUMBING
J 0
(4575 2350);
DISPLAY 0.872340 (4575 2350);
PAINT GREEN (4575 2350);
DISPLAY INVISIBLE (4575 2350);
FORCEPROP 1 LAST HDL_TAP TRUE
J 0
(4900 2175);
DISPLAY 0.872340 (4900 2175);
DISPLAY INVISIBLE (4900 2175);
FORCEPROP 1 LAST PATH I194
J 0
(4573 2300);
DISPLAY 0.872340 (4573 2300);
PAINT GREEN (4573 2300);
DISPLAY INVISIBLE (4573 2300);
FORCEADD TAP..1
(4575 2500);
FORCEPROP 3 LASTPIN (4525 2500) SIG_NAME P5E_CPU0_P3_TX_C_DP<10>
J 0
(4535 2510);
DISPLAY 0.659574 (4535 2510);
PAINT MONO (4535 2510);
DISPLAY INVISIBLE (4535 2510);
FORCEPROP 1 LASTPIN (4525 2500) BN 10
J 0
(4513 2508);
DISPLAY 0.680851 (4513 2508);
PAINT GREEN (4513 2508);
FORCEPROP 2 LAST CDS_LIB standard
J 0
(4575 2500);
DISPLAY INVISIBLE (4575 2500);
FORCEPROP 1 LAST BODY_TYPE PLUMBING
J 0
(4575 2550);
DISPLAY 0.872340 (4575 2550);
PAINT GREEN (4575 2550);
DISPLAY INVISIBLE (4575 2550);
FORCEPROP 1 LAST HDL_TAP TRUE
J 0
(4900 2375);
DISPLAY 0.872340 (4900 2375);
DISPLAY INVISIBLE (4900 2375);
FORCEPROP 1 LAST PATH I195
J 0
(4573 2500);
DISPLAY 0.872340 (4573 2500);
PAINT GREEN (4573 2500);
DISPLAY INVISIBLE (4573 2500);
FORCEADD TAP..1
(4575 2700);
FORCEPROP 3 LASTPIN (4525 2700) SIG_NAME P5E_CPU0_P3_TX_C_DP<11>
J 0
(4535 2710);
DISPLAY 0.659574 (4535 2710);
PAINT MONO (4535 2710);
DISPLAY INVISIBLE (4535 2710);
FORCEPROP 1 LASTPIN (4525 2700) BN 11
J 0
(4513 2708);
DISPLAY 0.680851 (4513 2708);
PAINT GREEN (4513 2708);
FORCEPROP 2 LAST CDS_LIB standard
J 0
(4575 2700);
DISPLAY INVISIBLE (4575 2700);
FORCEPROP 1 LAST BODY_TYPE PLUMBING
J 0
(4575 2750);
DISPLAY 0.872340 (4575 2750);
PAINT GREEN (4575 2750);
DISPLAY INVISIBLE (4575 2750);
FORCEPROP 1 LAST HDL_TAP TRUE
J 0
(4900 2575);
DISPLAY 0.872340 (4900 2575);
DISPLAY INVISIBLE (4900 2575);
FORCEPROP 1 LAST PATH I196
J 0
(4573 2700);
DISPLAY 0.872340 (4573 2700);
PAINT GREEN (4573 2700);
DISPLAY INVISIBLE (4573 2700);
FORCEADD TAP..1
(4575 2900);
FORCEPROP 3 LASTPIN (4525 2900) SIG_NAME P5E_CPU0_P3_TX_C_DP<12>
J 0
(4535 2910);
DISPLAY 0.659574 (4535 2910);
PAINT MONO (4535 2910);
DISPLAY INVISIBLE (4535 2910);
FORCEPROP 1 LASTPIN (4525 2900) BN 12
J 0
(4513 2908);
DISPLAY 0.680851 (4513 2908);
PAINT GREEN (4513 2908);
FORCEPROP 2 LAST CDS_LIB standard
J 0
(4575 2900);
DISPLAY INVISIBLE (4575 2900);
FORCEPROP 1 LAST BODY_TYPE PLUMBING
J 0
(4575 2950);
DISPLAY 0.872340 (4575 2950);
PAINT GREEN (4575 2950);
DISPLAY INVISIBLE (4575 2950);
FORCEPROP 1 LAST HDL_TAP TRUE
J 0
(4900 2775);
DISPLAY 0.872340 (4900 2775);
DISPLAY INVISIBLE (4900 2775);
FORCEPROP 1 LAST PATH I197
J 0
(4573 2900);
DISPLAY 0.872340 (4573 2900);
PAINT GREEN (4573 2900);
DISPLAY INVISIBLE (4573 2900);
FORCEADD TAP..1
(4375 3150);
FORCEPROP 3 LASTPIN (4325 3150) SIG_NAME P5E_CPU0_P3_TX_C_DN<13>
J 0
(4335 3160);
DISPLAY 0.659574 (4335 3160);
PAINT MONO (4335 3160);
DISPLAY INVISIBLE (4335 3160);
FORCEPROP 1 LASTPIN (4325 3150) BN 13
J 0
(4313 3158);
DISPLAY 0.680851 (4313 3158);
PAINT GREEN (4313 3158);
FORCEPROP 2 LAST CDS_LIB standard
J 0
(4375 3150);
DISPLAY INVISIBLE (4375 3150);
FORCEPROP 1 LAST BODY_TYPE PLUMBING
J 0
(4375 3200);
DISPLAY 0.872340 (4375 3200);
PAINT GREEN (4375 3200);
DISPLAY INVISIBLE (4375 3200);
FORCEPROP 1 LAST HDL_TAP TRUE
J 0
(4700 3025);
DISPLAY 0.872340 (4700 3025);
DISPLAY INVISIBLE (4700 3025);
FORCEPROP 1 LAST PATH I198
J 0
(4373 3150);
DISPLAY 0.872340 (4373 3150);
PAINT GREEN (4373 3150);
DISPLAY INVISIBLE (4373 3150);
FORCEADD TAP..1
(4375 3550);
FORCEPROP 3 LASTPIN (4325 3550) SIG_NAME P5E_CPU0_P3_TX_C_DN<15>
J 0
(4335 3560);
DISPLAY 0.659574 (4335 3560);
PAINT MONO (4335 3560);
DISPLAY INVISIBLE (4335 3560);
FORCEPROP 1 LASTPIN (4325 3550) BN 15
J 0
(4313 3558);
DISPLAY 0.680851 (4313 3558);
PAINT GREEN (4313 3558);
FORCEPROP 2 LAST CDS_LIB standard
J 0
(4375 3550);
DISPLAY INVISIBLE (4375 3550);
FORCEPROP 1 LAST BODY_TYPE PLUMBING
J 0
(4375 3600);
DISPLAY 0.872340 (4375 3600);
PAINT GREEN (4375 3600);
DISPLAY INVISIBLE (4375 3600);
FORCEPROP 1 LAST HDL_TAP TRUE
J 0
(4700 3425);
DISPLAY 0.872340 (4700 3425);
DISPLAY INVISIBLE (4700 3425);
FORCEPROP 1 LAST PATH I199
J 0
(4373 3550);
DISPLAY 0.872340 (4373 3550);
PAINT GREEN (4373 3550);
DISPLAY INVISIBLE (4373 3550);
FORCEADD OFFPAGE..1
(-2575 1550);
FORCEPROP 2 LAST $XR0 25 
J 0
(-2796 1550);
DISPLAY 0.638298 (-2796 1550);
PAINT MONO (-2796 1550);
FORCEPROP 2 LAST CDS_LIB standard
J 0
(-2575 1550);
DISPLAY INVISIBLE (-2575 1550);
FORCEPROP 1 LAST OFFPAGE TRUE
J 0
(-2250 1425);
DISPLAY 0.872340 (-2250 1425);
DISPLAY INVISIBLE (-2250 1425);
FORCEPROP 1 LAST COMMENT_BODY TRUE
J 0
(-2450 1450);
DISPLAY 0.872340 (-2450 1450);
PAINT GREEN (-2450 1450);
DISPLAY INVISIBLE (-2450 1450);
FORCEPROP 2 LAST PATH I2
J 0
(-2825 1600);
DISPLAY 1.021277 (-2825 1600);
DISPLAY INVISIBLE (-2825 1600);
FORCEADD TAP..1
R 2
(-1375 1575);
FORCEPROP 3 LASTPIN (-1325 1575) SIG_NAME P5E_CPU0_P2_TX_DN<7>
J 0
(-1315 1585);
DISPLAY 0.659574 (-1315 1585);
PAINT MONO (-1315 1585);
DISPLAY INVISIBLE (-1315 1585);
FORCEPROP 1 LASTPIN (-1325 1575) BN 7
J 2
(-1313 1583);
DISPLAY 0.680851 (-1313 1583);
PAINT GREEN (-1313 1583);
FORCEPROP 2 LAST CDS_LIB standard
J 0
(-1375 1575);
DISPLAY INVISIBLE (-1375 1575);
FORCEPROP 1 LAST BODY_TYPE PLUMBING
J 2
(-1375 1625);
DISPLAY 0.872340 (-1375 1625);
PAINT GREEN (-1375 1625);
DISPLAY INVISIBLE (-1375 1625);
FORCEPROP 1 LAST HDL_TAP TRUE
J 2
(-1700 1450);
DISPLAY 0.872340 (-1700 1450);
DISPLAY INVISIBLE (-1700 1450);
FORCEPROP 1 LAST PATH I20
J 2
(-1373 1575);
DISPLAY 0.872340 (-1373 1575);
PAINT GREEN (-1373 1575);
DISPLAY INVISIBLE (-1373 1575);
FORCEADD TAP..1
(4375 3350);
FORCEPROP 3 LASTPIN (4325 3350) SIG_NAME P5E_CPU0_P3_TX_C_DN<14>
J 0
(4335 3360);
DISPLAY 0.659574 (4335 3360);
PAINT MONO (4335 3360);
DISPLAY INVISIBLE (4335 3360);
FORCEPROP 1 LASTPIN (4325 3350) BN 14
J 0
(4313 3358);
DISPLAY 0.680851 (4313 3358);
PAINT GREEN (4313 3358);
FORCEPROP 2 LAST CDS_LIB standard
J 0
(4375 3350);
DISPLAY INVISIBLE (4375 3350);
FORCEPROP 1 LAST BODY_TYPE PLUMBING
J 0
(4375 3400);
DISPLAY 0.872340 (4375 3400);
PAINT GREEN (4375 3400);
DISPLAY INVISIBLE (4375 3400);
FORCEPROP 1 LAST HDL_TAP TRUE
J 0
(4700 3225);
DISPLAY 0.872340 (4700 3225);
DISPLAY INVISIBLE (4700 3225);
FORCEPROP 1 LAST PATH I200
J 0
(4373 3350);
DISPLAY 0.872340 (4373 3350);
PAINT GREEN (4373 3350);
DISPLAY INVISIBLE (4373 3350);
FORCEADD TAP..1
(4575 3100);
FORCEPROP 3 LASTPIN (4525 3100) SIG_NAME P5E_CPU0_P3_TX_C_DP<13>
J 0
(4535 3110);
DISPLAY 0.659574 (4535 3110);
PAINT MONO (4535 3110);
DISPLAY INVISIBLE (4535 3110);
FORCEPROP 1 LASTPIN (4525 3100) BN 13
J 0
(4513 3108);
DISPLAY 0.680851 (4513 3108);
PAINT GREEN (4513 3108);
FORCEPROP 2 LAST CDS_LIB standard
J 0
(4575 3100);
DISPLAY INVISIBLE (4575 3100);
FORCEPROP 1 LAST BODY_TYPE PLUMBING
J 0
(4575 3150);
DISPLAY 0.872340 (4575 3150);
PAINT GREEN (4575 3150);
DISPLAY INVISIBLE (4575 3150);
FORCEPROP 1 LAST HDL_TAP TRUE
J 0
(4900 2975);
DISPLAY 0.872340 (4900 2975);
DISPLAY INVISIBLE (4900 2975);
FORCEPROP 1 LAST PATH I201
J 0
(4573 3100);
DISPLAY 0.872340 (4573 3100);
PAINT GREEN (4573 3100);
DISPLAY INVISIBLE (4573 3100);
FORCEADD TAP..1
(4575 3300);
FORCEPROP 3 LASTPIN (4525 3300) SIG_NAME P5E_CPU0_P3_TX_C_DP<14>
J 0
(4535 3310);
DISPLAY 0.659574 (4535 3310);
PAINT MONO (4535 3310);
DISPLAY INVISIBLE (4535 3310);
FORCEPROP 1 LASTPIN (4525 3300) BN 14
J 0
(4513 3308);
DISPLAY 0.680851 (4513 3308);
PAINT GREEN (4513 3308);
FORCEPROP 2 LAST CDS_LIB standard
J 0
(4575 3300);
DISPLAY INVISIBLE (4575 3300);
FORCEPROP 1 LAST BODY_TYPE PLUMBING
J 0
(4575 3350);
DISPLAY 0.872340 (4575 3350);
PAINT GREEN (4575 3350);
DISPLAY INVISIBLE (4575 3350);
FORCEPROP 1 LAST HDL_TAP TRUE
J 0
(4900 3175);
DISPLAY 0.872340 (4900 3175);
DISPLAY INVISIBLE (4900 3175);
FORCEPROP 1 LAST PATH I202
J 0
(4573 3300);
DISPLAY 0.872340 (4573 3300);
PAINT GREEN (4573 3300);
DISPLAY INVISIBLE (4573 3300);
FORCEADD TAP..1
(4575 3500);
FORCEPROP 3 LASTPIN (4525 3500) SIG_NAME P5E_CPU0_P3_TX_C_DP<15>
J 0
(4535 3510);
DISPLAY 0.659574 (4535 3510);
PAINT MONO (4535 3510);
DISPLAY INVISIBLE (4535 3510);
FORCEPROP 1 LASTPIN (4525 3500) BN 15
J 0
(4513 3508);
DISPLAY 0.680851 (4513 3508);
PAINT GREEN (4513 3508);
FORCEPROP 2 LAST CDS_LIB standard
J 0
(4575 3500);
DISPLAY INVISIBLE (4575 3500);
FORCEPROP 1 LAST BODY_TYPE PLUMBING
J 0
(4575 3550);
DISPLAY 0.872340 (4575 3550);
PAINT GREEN (4575 3550);
DISPLAY INVISIBLE (4575 3550);
FORCEPROP 1 LAST HDL_TAP TRUE
J 0
(4900 3375);
DISPLAY 0.872340 (4900 3375);
DISPLAY INVISIBLE (4900 3375);
FORCEPROP 1 LAST PATH I203
J 0
(4573 3500);
DISPLAY 0.872340 (4573 3500);
PAINT GREEN (4573 3500);
DISPLAY INVISIBLE (4573 3500);
FORCEADD OFFPAGE..2
(5575 3575);
FORCEPROP 2 LAST $XR0 306 
J 0
(5764 3575);
DISPLAY 0.638298 (5764 3575);
PAINT MONO (5764 3575);
FORCEPROP 2 LAST CDS_LIB standard
J 0
(5575 3575);
DISPLAY INVISIBLE (5575 3575);
FORCEPROP 1 LAST OFFPAGE TRUE
J 0
(5900 3450);
DISPLAY 0.872340 (5900 3450);
DISPLAY INVISIBLE (5900 3450);
FORCEPROP 1 LAST COMMENT_BODY TRUE
J 0
(5530 3480);
DISPLAY 0.872340 (5530 3480);
PAINT GREEN (5530 3480);
DISPLAY INVISIBLE (5530 3480);
FORCEPROP 2 LAST PATH I204
J 0
(5775 3625);
DISPLAY 1.021277 (5775 3625);
DISPLAY INVISIBLE (5775 3625);
FORCEADD OFFPAGE..2
(5575 3525);
FORCEPROP 2 LAST $XR0 306 
J 0
(5764 3525);
DISPLAY 0.638298 (5764 3525);
PAINT MONO (5764 3525);
FORCEPROP 2 LAST CDS_LIB standard
J 0
(5575 3525);
DISPLAY INVISIBLE (5575 3525);
FORCEPROP 1 LAST OFFPAGE TRUE
J 0
(5900 3400);
DISPLAY 0.872340 (5900 3400);
DISPLAY INVISIBLE (5900 3400);
FORCEPROP 1 LAST COMMENT_BODY TRUE
J 0
(5530 3430);
DISPLAY 0.872340 (5530 3430);
PAINT GREEN (5530 3430);
DISPLAY INVISIBLE (5530 3430);
FORCEPROP 2 LAST PATH I205
J 0
(5775 3575);
DISPLAY 1.021277 (5775 3575);
DISPLAY INVISIBLE (5775 3575);
FORCEADD Q_CAP_DIFFBUS..2
R 2
(3825 375);
FORCEPROP 1 LAST LOCATION C898
J 2
(4059 392);
DISPLAY 0.723404 (4059 392);
PAINT GREEN (4059 392);
FORCEPROP 2 LAST $SEC 1
J 2
(4000 450);
DISPLAY 0.680851 (4000 450);
PAINT MONO (4000 450);
DISPLAY INVISIBLE (4000 450);
FORCEPROP 2 LAST CDS_SEC 1
J 2
(4000 450);
DISPLAY 0.680851 (4000 450);
DISPLAY INVISIBLE (4000 450);
FORCEPROP 2 LASTPIN (3900 375) $PN 1
J 0
(3910 385);
DISPLAY 0.808511 (3910 385);
FORCEPROP 2 LASTPIN (3750 375) $PN 2
J 2
(3740 385);
DISPLAY 0.808511 (3740 385);
FORCEPROP 2 LAST VALUE DIFF BUS_0.22UF
J 2
(3675 375);
DISPLAY 0.553191 (3675 375);
FORCEPROP 1 LAST PIN_NAMES_ROTATE TRUE
J 2
(3825 375);
DISPLAY 0.489362 (3825 375);
PAINT GREEN (3825 375);
DISPLAY INVISIBLE (3825 375);
FORCEPROP 1 LAST CDS_LMAN_SYM_OUTLINE -25,50,25,-50
J 2
(3825 375);
DISPLAY 0.468085 (3825 375);
PAINT GREEN (3825 375);
DISPLAY INVISIBLE (3825 375);
FORCEPROP 2 LAST CDS_LIB pure_quanta
J 2
(3825 375);
DISPLAY INVISIBLE (3825 375);
FORCEPROP 2 LAST VOLTAGE 6.3V
J 2
(3475 425);
DISPLAY 0.553191 (3475 425);
DISPLAY INVISIBLE (3475 425);
FORCEPROP 1 LAST MATERIAL X6S
J 2
(3834 454);
DISPLAY 0.574468 (3834 454);
PAINT GREEN (3834 454);
DISPLAY INVISIBLE (3834 454);
FORCEPROP 2 LAST PACK_TYPE C0201
J 2
(3650 425);
DISPLAY 0.553191 (3650 425);
DISPLAY INVISIBLE (3650 425);
FORCEPROP 2 LAST TOLERANCE 20%
J 2
(3750 425);
DISPLAY 0.553191 (3750 425);
DISPLAY INVISIBLE (3750 425);
FORCEPROP 1 LAST PART_NUMBER SP_CH4221MEE01
J 2
(3709 463);
DISPLAY 0.574468 (3709 463);
PAINT GREEN (3709 463);
DISPLAY INVISIBLE (3709 463);
FORCEPROP 1 LAST LOCATION C898
J 0
(4075 450);
DISPLAY 1.021277 (4075 450);
DISPLAY INVISIBLE (4075 450);
FORCEPROP 1 LAST PATH I206
J 2
(3825 375);
DISPLAY 0.723404 (3825 375);
DISPLAY INVISIBLE (3825 375);
FORCEADD TAP..1
R 2
(3100 975);
FORCEPROP 3 LASTPIN (3150 975) SIG_NAME P5E_CPU0_P3_TX_DN<4>
J 0
(3160 985);
DISPLAY 0.659574 (3160 985);
PAINT MONO (3160 985);
DISPLAY INVISIBLE (3160 985);
FORCEPROP 1 LASTPIN (3150 975) BN 4
J 2
(3162 983);
DISPLAY 0.680851 (3162 983);
PAINT GREEN (3162 983);
FORCEPROP 2 LAST CDS_LIB standard
J 0
(3100 975);
DISPLAY INVISIBLE (3100 975);
FORCEPROP 1 LAST BODY_TYPE PLUMBING
J 2
(3100 1025);
DISPLAY 0.872340 (3100 1025);
PAINT GREEN (3100 1025);
DISPLAY INVISIBLE (3100 1025);
FORCEPROP 1 LAST HDL_TAP TRUE
J 2
(2775 850);
DISPLAY 0.872340 (2775 850);
DISPLAY INVISIBLE (2775 850);
FORCEPROP 1 LAST PATH I207
J 2
(3102 975);
DISPLAY 0.872340 (3102 975);
PAINT GREEN (3102 975);
DISPLAY INVISIBLE (3102 975);
FORCEADD TAP..1
R 2
(2850 1125);
FORCEPROP 3 LASTPIN (2900 1125) SIG_NAME P5E_CPU0_P3_TX_DP<5>
J 0
(2910 1135);
DISPLAY 0.659574 (2910 1135);
PAINT MONO (2910 1135);
DISPLAY INVISIBLE (2910 1135);
FORCEPROP 1 LASTPIN (2900 1125) BN 5
J 2
(2912 1133);
DISPLAY 0.680851 (2912 1133);
PAINT GREEN (2912 1133);
FORCEPROP 2 LAST CDS_LIB standard
J 0
(2850 1125);
DISPLAY INVISIBLE (2850 1125);
FORCEPROP 1 LAST BODY_TYPE PLUMBING
J 2
(2850 1175);
DISPLAY 0.872340 (2850 1175);
PAINT GREEN (2850 1175);
DISPLAY INVISIBLE (2850 1175);
FORCEPROP 1 LAST HDL_TAP TRUE
J 2
(2525 1000);
DISPLAY 0.872340 (2525 1000);
DISPLAY INVISIBLE (2525 1000);
FORCEPROP 1 LAST PATH I208
J 2
(2852 1125);
DISPLAY 0.872340 (2852 1125);
PAINT GREEN (2852 1125);
DISPLAY INVISIBLE (2852 1125);
FORCEADD Q_CAP_DIFFBUS..2
R 2
(-650 125);
FORCEPROP 1 LAST LOCATION C869
J 2
(-416 142);
DISPLAY 0.723404 (-416 142);
PAINT GREEN (-416 142);
FORCEPROP 2 LAST $SEC 1
J 2
(-475 200);
DISPLAY 0.680851 (-475 200);
PAINT MONO (-475 200);
DISPLAY INVISIBLE (-475 200);
FORCEPROP 2 LAST CDS_SEC 1
J 2
(-475 200);
DISPLAY 0.680851 (-475 200);
DISPLAY INVISIBLE (-475 200);
FORCEPROP 2 LASTPIN (-575 125) $PN 1
J 0
(-565 135);
DISPLAY 0.808511 (-565 135);
FORCEPROP 2 LASTPIN (-725 125) $PN 2
J 2
(-735 135);
DISPLAY 0.808511 (-735 135);
FORCEPROP 2 LAST VALUE DIFF BUS_0.22UF
J 2
(-800 125);
DISPLAY 0.553191 (-800 125);
FORCEPROP 2 LAST TOLERANCE 20%
J 2
(-725 175);
DISPLAY 0.553191 (-725 175);
DISPLAY INVISIBLE (-725 175);
FORCEPROP 2 LAST PACK_TYPE C0201
J 2
(-825 175);
DISPLAY 0.553191 (-825 175);
DISPLAY INVISIBLE (-825 175);
FORCEPROP 1 LAST MATERIAL X6S
J 2
(-641 204);
DISPLAY 0.574468 (-641 204);
PAINT GREEN (-641 204);
DISPLAY INVISIBLE (-641 204);
FORCEPROP 2 LAST VOLTAGE 6.3V
J 2
(-1000 175);
DISPLAY 0.553191 (-1000 175);
DISPLAY INVISIBLE (-1000 175);
FORCEPROP 1 LAST CDS_LMAN_SYM_OUTLINE -25,50,25,-50
J 2
(-650 125);
DISPLAY 0.468085 (-650 125);
PAINT GREEN (-650 125);
DISPLAY INVISIBLE (-650 125);
FORCEPROP 2 LAST CDS_LIB pure_quanta
J 2
(-650 125);
DISPLAY INVISIBLE (-650 125);
FORCEPROP 1 LAST PIN_NAMES_ROTATE TRUE
J 2
(-650 125);
DISPLAY 0.489362 (-650 125);
PAINT GREEN (-650 125);
DISPLAY INVISIBLE (-650 125);
FORCEPROP 1 LAST PART_NUMBER SP_CH4221MEE01
J 2
(-766 213);
DISPLAY 0.574468 (-766 213);
PAINT GREEN (-766 213);
DISPLAY INVISIBLE (-766 213);
FORCEPROP 1 LAST LOCATION C869
J 0
(-400 200);
DISPLAY 1.021277 (-400 200);
DISPLAY INVISIBLE (-400 200);
FORCEPROP 1 LAST PATH I21
J 2
(-650 125);
DISPLAY 0.723404 (-650 125);
DISPLAY INVISIBLE (-650 125);
FORCEADD Q_CAP_DIFFBUS..2
R 2
(-650 175);
FORCEPROP 1 LAST LOCATION C868
J 2
(-416 192);
DISPLAY 0.723404 (-416 192);
PAINT GREEN (-416 192);
FORCEPROP 2 LAST $SEC 1
J 2
(-475 250);
DISPLAY 0.680851 (-475 250);
PAINT MONO (-475 250);
DISPLAY INVISIBLE (-475 250);
FORCEPROP 2 LAST CDS_SEC 1
J 2
(-475 250);
DISPLAY 0.680851 (-475 250);
DISPLAY INVISIBLE (-475 250);
FORCEPROP 2 LASTPIN (-575 175) $PN 1
J 0
(-565 185);
DISPLAY 0.808511 (-565 185);
FORCEPROP 2 LASTPIN (-725 175) $PN 2
J 2
(-735 185);
DISPLAY 0.808511 (-735 185);
FORCEPROP 2 LAST VALUE DIFF BUS_0.22UF
J 2
(-800 175);
DISPLAY 0.553191 (-800 175);
FORCEPROP 2 LAST TOLERANCE 20%
J 2
(-725 225);
DISPLAY 0.553191 (-725 225);
DISPLAY INVISIBLE (-725 225);
FORCEPROP 2 LAST PACK_TYPE C0201
J 2
(-825 225);
DISPLAY 0.553191 (-825 225);
DISPLAY INVISIBLE (-825 225);
FORCEPROP 1 LAST MATERIAL X6S
J 2
(-641 254);
DISPLAY 0.574468 (-641 254);
PAINT GREEN (-641 254);
DISPLAY INVISIBLE (-641 254);
FORCEPROP 2 LAST VOLTAGE 6.3V
J 2
(-1000 225);
DISPLAY 0.553191 (-1000 225);
DISPLAY INVISIBLE (-1000 225);
FORCEPROP 1 LAST CDS_LMAN_SYM_OUTLINE -25,50,25,-50
J 2
(-650 175);
DISPLAY 0.468085 (-650 175);
PAINT GREEN (-650 175);
DISPLAY INVISIBLE (-650 175);
FORCEPROP 2 LAST CDS_LIB pure_quanta
J 2
(-650 175);
DISPLAY INVISIBLE (-650 175);
FORCEPROP 1 LAST PIN_NAMES_ROTATE TRUE
J 2
(-650 175);
DISPLAY 0.489362 (-650 175);
PAINT GREEN (-650 175);
DISPLAY INVISIBLE (-650 175);
FORCEPROP 1 LAST PART_NUMBER SP_CH4221MEE01
J 2
(-766 263);
DISPLAY 0.574468 (-766 263);
PAINT GREEN (-766 263);
DISPLAY INVISIBLE (-766 263);
FORCEPROP 1 LAST LOCATION C868
J 0
(-400 250);
DISPLAY 1.021277 (-400 250);
DISPLAY INVISIBLE (-400 250);
FORCEPROP 1 LAST PATH I22
J 2
(-650 175);
DISPLAY 0.723404 (-650 175);
DISPLAY INVISIBLE (-650 175);
FORCEADD Q_CAP_DIFFBUS..2
R 2
(-650 325);
FORCEPROP 1 LAST LOCATION C867
J 2
(-416 342);
DISPLAY 0.723404 (-416 342);
PAINT GREEN (-416 342);
FORCEPROP 2 LAST $SEC 1
J 2
(-475 400);
DISPLAY 0.680851 (-475 400);
PAINT MONO (-475 400);
DISPLAY INVISIBLE (-475 400);
FORCEPROP 2 LAST CDS_SEC 1
J 2
(-475 400);
DISPLAY 0.680851 (-475 400);
DISPLAY INVISIBLE (-475 400);
FORCEPROP 2 LASTPIN (-575 325) $PN 1
J 0
(-565 335);
DISPLAY 0.808511 (-565 335);
FORCEPROP 2 LASTPIN (-725 325) $PN 2
J 2
(-735 335);
DISPLAY 0.808511 (-735 335);
FORCEPROP 2 LAST VALUE DIFF BUS_0.22UF
J 2
(-800 325);
DISPLAY 0.553191 (-800 325);
FORCEPROP 2 LAST TOLERANCE 20%
J 2
(-725 375);
DISPLAY 0.553191 (-725 375);
DISPLAY INVISIBLE (-725 375);
FORCEPROP 2 LAST PACK_TYPE C0201
J 2
(-825 375);
DISPLAY 0.553191 (-825 375);
DISPLAY INVISIBLE (-825 375);
FORCEPROP 1 LAST MATERIAL X6S
J 2
(-641 404);
DISPLAY 0.574468 (-641 404);
PAINT GREEN (-641 404);
DISPLAY INVISIBLE (-641 404);
FORCEPROP 2 LAST VOLTAGE 6.3V
J 2
(-1000 375);
DISPLAY 0.553191 (-1000 375);
DISPLAY INVISIBLE (-1000 375);
FORCEPROP 1 LAST CDS_LMAN_SYM_OUTLINE -25,50,25,-50
J 2
(-650 325);
DISPLAY 0.468085 (-650 325);
PAINT GREEN (-650 325);
DISPLAY INVISIBLE (-650 325);
FORCEPROP 2 LAST CDS_LIB pure_quanta
J 2
(-650 325);
DISPLAY INVISIBLE (-650 325);
FORCEPROP 1 LAST PIN_NAMES_ROTATE TRUE
J 2
(-650 325);
DISPLAY 0.489362 (-650 325);
PAINT GREEN (-650 325);
DISPLAY INVISIBLE (-650 325);
FORCEPROP 1 LAST PART_NUMBER SP_CH4221MEE01
J 2
(-766 413);
DISPLAY 0.574468 (-766 413);
PAINT GREEN (-766 413);
DISPLAY INVISIBLE (-766 413);
FORCEPROP 1 LAST LOCATION C867
J 0
(-400 400);
DISPLAY 1.021277 (-400 400);
DISPLAY INVISIBLE (-400 400);
FORCEPROP 1 LAST PATH I23
J 2
(-650 325);
DISPLAY 0.723404 (-650 325);
DISPLAY INVISIBLE (-650 325);
FORCEADD Q_CAP_DIFFBUS..2
R 2
(-650 375);
FORCEPROP 1 LAST LOCATION C866
J 2
(-416 392);
DISPLAY 0.723404 (-416 392);
PAINT GREEN (-416 392);
FORCEPROP 2 LAST $SEC 1
J 2
(-475 450);
DISPLAY 0.680851 (-475 450);
PAINT MONO (-475 450);
DISPLAY INVISIBLE (-475 450);
FORCEPROP 2 LAST CDS_SEC 1
J 2
(-475 450);
DISPLAY 0.680851 (-475 450);
DISPLAY INVISIBLE (-475 450);
FORCEPROP 2 LASTPIN (-575 375) $PN 1
J 0
(-565 385);
DISPLAY 0.808511 (-565 385);
FORCEPROP 2 LASTPIN (-725 375) $PN 2
J 2
(-735 385);
DISPLAY 0.808511 (-735 385);
FORCEPROP 2 LAST VALUE DIFF BUS_0.22UF
J 2
(-800 375);
DISPLAY 0.553191 (-800 375);
FORCEPROP 2 LAST TOLERANCE 20%
J 2
(-725 425);
DISPLAY 0.553191 (-725 425);
DISPLAY INVISIBLE (-725 425);
FORCEPROP 2 LAST PACK_TYPE C0201
J 2
(-825 425);
DISPLAY 0.553191 (-825 425);
DISPLAY INVISIBLE (-825 425);
FORCEPROP 1 LAST MATERIAL X6S
J 2
(-641 454);
DISPLAY 0.574468 (-641 454);
PAINT GREEN (-641 454);
DISPLAY INVISIBLE (-641 454);
FORCEPROP 2 LAST VOLTAGE 6.3V
J 2
(-1000 425);
DISPLAY 0.553191 (-1000 425);
DISPLAY INVISIBLE (-1000 425);
FORCEPROP 2 LAST CDS_LIB pure_quanta
J 2
(-650 375);
DISPLAY INVISIBLE (-650 375);
FORCEPROP 1 LAST CDS_LMAN_SYM_OUTLINE -25,50,25,-50
J 2
(-650 375);
DISPLAY 0.468085 (-650 375);
PAINT GREEN (-650 375);
DISPLAY INVISIBLE (-650 375);
FORCEPROP 1 LAST PIN_NAMES_ROTATE TRUE
J 2
(-650 375);
DISPLAY 0.489362 (-650 375);
PAINT GREEN (-650 375);
DISPLAY INVISIBLE (-650 375);
FORCEPROP 1 LAST PART_NUMBER SP_CH4221MEE01
J 2
(-766 463);
DISPLAY 0.574468 (-766 463);
PAINT GREEN (-766 463);
DISPLAY INVISIBLE (-766 463);
FORCEPROP 1 LAST LOCATION C866
J 0
(-400 450);
DISPLAY 1.021277 (-400 450);
DISPLAY INVISIBLE (-400 450);
FORCEPROP 1 LAST PATH I24
J 2
(-650 375);
DISPLAY 0.723404 (-650 375);
DISPLAY INVISIBLE (-650 375);
FORCEADD Q_CAP_DIFFBUS..2
R 2
(-650 575);
FORCEPROP 1 LAST LOCATION C864
J 2
(-416 592);
DISPLAY 0.723404 (-416 592);
PAINT GREEN (-416 592);
FORCEPROP 2 LAST $SEC 1
J 2
(-475 650);
DISPLAY 0.680851 (-475 650);
PAINT MONO (-475 650);
DISPLAY INVISIBLE (-475 650);
FORCEPROP 2 LAST CDS_SEC 1
J 2
(-475 650);
DISPLAY 0.680851 (-475 650);
DISPLAY INVISIBLE (-475 650);
FORCEPROP 2 LASTPIN (-575 575) $PN 1
J 0
(-565 585);
DISPLAY 0.808511 (-565 585);
FORCEPROP 2 LASTPIN (-725 575) $PN 2
J 2
(-735 585);
DISPLAY 0.808511 (-735 585);
FORCEPROP 2 LAST VALUE DIFF BUS_0.22UF
J 2
(-800 575);
DISPLAY 0.553191 (-800 575);
FORCEPROP 2 LAST TOLERANCE 20%
J 2
(-725 625);
DISPLAY 0.553191 (-725 625);
DISPLAY INVISIBLE (-725 625);
FORCEPROP 2 LAST PACK_TYPE C0201
J 2
(-825 625);
DISPLAY 0.553191 (-825 625);
DISPLAY INVISIBLE (-825 625);
FORCEPROP 1 LAST MATERIAL X6S
J 2
(-641 654);
DISPLAY 0.574468 (-641 654);
PAINT GREEN (-641 654);
DISPLAY INVISIBLE (-641 654);
FORCEPROP 2 LAST VOLTAGE 6.3V
J 2
(-1000 625);
DISPLAY 0.553191 (-1000 625);
DISPLAY INVISIBLE (-1000 625);
FORCEPROP 1 LAST CDS_LMAN_SYM_OUTLINE -25,50,25,-50
J 2
(-650 575);
DISPLAY 0.468085 (-650 575);
PAINT GREEN (-650 575);
DISPLAY INVISIBLE (-650 575);
FORCEPROP 2 LAST CDS_LIB pure_quanta
J 2
(-650 575);
DISPLAY INVISIBLE (-650 575);
FORCEPROP 1 LAST PIN_NAMES_ROTATE TRUE
J 2
(-650 575);
DISPLAY 0.489362 (-650 575);
PAINT GREEN (-650 575);
DISPLAY INVISIBLE (-650 575);
FORCEPROP 1 LAST PART_NUMBER SP_CH4221MEE01
J 2
(-766 663);
DISPLAY 0.574468 (-766 663);
PAINT GREEN (-766 663);
DISPLAY INVISIBLE (-766 663);
FORCEPROP 1 LAST LOCATION C864
J 0
(-400 650);
DISPLAY 1.021277 (-400 650);
DISPLAY INVISIBLE (-400 650);
FORCEPROP 1 LAST PATH I25
J 2
(-650 575);
DISPLAY 0.723404 (-650 575);
DISPLAY INVISIBLE (-650 575);
FORCEADD Q_CAP_DIFFBUS..2
R 2
(-650 525);
FORCEPROP 1 LAST LOCATION C865
J 2
(-416 542);
DISPLAY 0.723404 (-416 542);
PAINT GREEN (-416 542);
FORCEPROP 2 LAST $SEC 1
J 2
(-475 600);
DISPLAY 0.680851 (-475 600);
PAINT MONO (-475 600);
DISPLAY INVISIBLE (-475 600);
FORCEPROP 2 LAST CDS_SEC 1
J 2
(-475 600);
DISPLAY 0.680851 (-475 600);
DISPLAY INVISIBLE (-475 600);
FORCEPROP 2 LASTPIN (-575 525) $PN 1
J 0
(-565 535);
DISPLAY 0.808511 (-565 535);
FORCEPROP 2 LASTPIN (-725 525) $PN 2
J 2
(-735 535);
DISPLAY 0.808511 (-735 535);
FORCEPROP 2 LAST VALUE DIFF BUS_0.22UF
J 2
(-800 525);
DISPLAY 0.553191 (-800 525);
FORCEPROP 2 LAST TOLERANCE 20%
J 2
(-725 575);
DISPLAY 0.553191 (-725 575);
DISPLAY INVISIBLE (-725 575);
FORCEPROP 2 LAST PACK_TYPE C0201
J 2
(-825 575);
DISPLAY 0.553191 (-825 575);
DISPLAY INVISIBLE (-825 575);
FORCEPROP 1 LAST MATERIAL X6S
J 2
(-641 604);
DISPLAY 0.574468 (-641 604);
PAINT GREEN (-641 604);
DISPLAY INVISIBLE (-641 604);
FORCEPROP 2 LAST VOLTAGE 6.3V
J 2
(-1000 575);
DISPLAY 0.553191 (-1000 575);
DISPLAY INVISIBLE (-1000 575);
FORCEPROP 1 LAST CDS_LMAN_SYM_OUTLINE -25,50,25,-50
J 2
(-650 525);
DISPLAY 0.468085 (-650 525);
PAINT GREEN (-650 525);
DISPLAY INVISIBLE (-650 525);
FORCEPROP 2 LAST CDS_LIB pure_quanta
J 2
(-650 525);
DISPLAY INVISIBLE (-650 525);
FORCEPROP 1 LAST PIN_NAMES_ROTATE TRUE
J 2
(-650 525);
DISPLAY 0.489362 (-650 525);
PAINT GREEN (-650 525);
DISPLAY INVISIBLE (-650 525);
FORCEPROP 1 LAST PART_NUMBER SP_CH4221MEE01
J 2
(-766 613);
DISPLAY 0.574468 (-766 613);
PAINT GREEN (-766 613);
DISPLAY INVISIBLE (-766 613);
FORCEPROP 1 LAST LOCATION C865
J 0
(-400 600);
DISPLAY 1.021277 (-400 600);
DISPLAY INVISIBLE (-400 600);
FORCEPROP 1 LAST PATH I26
J 2
(-650 525);
DISPLAY 0.723404 (-650 525);
DISPLAY INVISIBLE (-650 525);
FORCEADD Q_CAP_DIFFBUS..2
R 2
(-650 725);
FORCEPROP 1 LAST LOCATION C863
J 2
(-416 742);
DISPLAY 0.723404 (-416 742);
PAINT GREEN (-416 742);
FORCEPROP 2 LAST $SEC 1
J 2
(-475 800);
DISPLAY 0.680851 (-475 800);
PAINT MONO (-475 800);
DISPLAY INVISIBLE (-475 800);
FORCEPROP 2 LAST CDS_SEC 1
J 2
(-475 800);
DISPLAY 0.680851 (-475 800);
DISPLAY INVISIBLE (-475 800);
FORCEPROP 2 LASTPIN (-575 725) $PN 1
J 0
(-565 735);
DISPLAY 0.808511 (-565 735);
FORCEPROP 2 LASTPIN (-725 725) $PN 2
J 2
(-735 735);
DISPLAY 0.808511 (-735 735);
FORCEPROP 2 LAST VALUE DIFF BUS_0.22UF
J 2
(-800 725);
DISPLAY 0.553191 (-800 725);
FORCEPROP 2 LAST TOLERANCE 20%
J 2
(-725 775);
DISPLAY 0.553191 (-725 775);
DISPLAY INVISIBLE (-725 775);
FORCEPROP 2 LAST PACK_TYPE C0201
J 2
(-825 775);
DISPLAY 0.553191 (-825 775);
DISPLAY INVISIBLE (-825 775);
FORCEPROP 1 LAST MATERIAL X6S
J 2
(-641 804);
DISPLAY 0.574468 (-641 804);
PAINT GREEN (-641 804);
DISPLAY INVISIBLE (-641 804);
FORCEPROP 2 LAST VOLTAGE 6.3V
J 2
(-1000 775);
DISPLAY 0.553191 (-1000 775);
DISPLAY INVISIBLE (-1000 775);
FORCEPROP 2 LAST CDS_LIB pure_quanta
J 2
(-650 725);
DISPLAY INVISIBLE (-650 725);
FORCEPROP 1 LAST CDS_LMAN_SYM_OUTLINE -25,50,25,-50
J 2
(-650 725);
DISPLAY 0.468085 (-650 725);
PAINT GREEN (-650 725);
DISPLAY INVISIBLE (-650 725);
FORCEPROP 1 LAST PIN_NAMES_ROTATE TRUE
J 2
(-650 725);
DISPLAY 0.489362 (-650 725);
PAINT GREEN (-650 725);
DISPLAY INVISIBLE (-650 725);
FORCEPROP 1 LAST PART_NUMBER SP_CH4221MEE01
J 2
(-766 813);
DISPLAY 0.574468 (-766 813);
PAINT GREEN (-766 813);
DISPLAY INVISIBLE (-766 813);
FORCEPROP 1 LAST LOCATION C863
J 0
(-400 800);
DISPLAY 1.021277 (-400 800);
DISPLAY INVISIBLE (-400 800);
FORCEPROP 1 LAST PATH I27
J 2
(-650 725);
DISPLAY 0.723404 (-650 725);
DISPLAY INVISIBLE (-650 725);
FORCEADD Q_CAP_DIFFBUS..2
R 2
(-650 775);
FORCEPROP 1 LAST LOCATION C862
J 2
(-416 792);
DISPLAY 0.723404 (-416 792);
PAINT GREEN (-416 792);
FORCEPROP 2 LAST $SEC 1
J 2
(-475 850);
DISPLAY 0.680851 (-475 850);
PAINT MONO (-475 850);
DISPLAY INVISIBLE (-475 850);
FORCEPROP 2 LAST CDS_SEC 1
J 2
(-475 850);
DISPLAY 0.680851 (-475 850);
DISPLAY INVISIBLE (-475 850);
FORCEPROP 2 LASTPIN (-575 775) $PN 1
J 0
(-565 785);
DISPLAY 0.808511 (-565 785);
FORCEPROP 2 LASTPIN (-725 775) $PN 2
J 2
(-735 785);
DISPLAY 0.808511 (-735 785);
FORCEPROP 2 LAST VALUE DIFF BUS_0.22UF
J 2
(-800 775);
DISPLAY 0.553191 (-800 775);
FORCEPROP 2 LAST TOLERANCE 20%
J 2
(-725 825);
DISPLAY 0.553191 (-725 825);
DISPLAY INVISIBLE (-725 825);
FORCEPROP 2 LAST PACK_TYPE C0201
J 2
(-825 825);
DISPLAY 0.553191 (-825 825);
DISPLAY INVISIBLE (-825 825);
FORCEPROP 1 LAST MATERIAL X6S
J 2
(-641 854);
DISPLAY 0.574468 (-641 854);
PAINT GREEN (-641 854);
DISPLAY INVISIBLE (-641 854);
FORCEPROP 2 LAST VOLTAGE 6.3V
J 2
(-1000 825);
DISPLAY 0.553191 (-1000 825);
DISPLAY INVISIBLE (-1000 825);
FORCEPROP 2 LAST CDS_LIB pure_quanta
J 2
(-650 775);
DISPLAY INVISIBLE (-650 775);
FORCEPROP 1 LAST CDS_LMAN_SYM_OUTLINE -25,50,25,-50
J 2
(-650 775);
DISPLAY 0.468085 (-650 775);
PAINT GREEN (-650 775);
DISPLAY INVISIBLE (-650 775);
FORCEPROP 1 LAST PIN_NAMES_ROTATE TRUE
J 2
(-650 775);
DISPLAY 0.489362 (-650 775);
PAINT GREEN (-650 775);
DISPLAY INVISIBLE (-650 775);
FORCEPROP 1 LAST PART_NUMBER SP_CH4221MEE01
J 2
(-766 863);
DISPLAY 0.574468 (-766 863);
PAINT GREEN (-766 863);
DISPLAY INVISIBLE (-766 863);
FORCEPROP 1 LAST LOCATION C862
J 0
(-400 850);
DISPLAY 1.021277 (-400 850);
DISPLAY INVISIBLE (-400 850);
FORCEPROP 1 LAST PATH I28
J 2
(-650 775);
DISPLAY 0.723404 (-650 775);
DISPLAY INVISIBLE (-650 775);
FORCEADD Q_CAP_DIFFBUS..2
R 2
(-650 925);
FORCEPROP 1 LAST LOCATION C861
J 2
(-416 942);
DISPLAY 0.723404 (-416 942);
PAINT GREEN (-416 942);
FORCEPROP 2 LAST $SEC 1
J 2
(-475 1000);
DISPLAY 0.680851 (-475 1000);
PAINT MONO (-475 1000);
DISPLAY INVISIBLE (-475 1000);
FORCEPROP 2 LAST CDS_SEC 1
J 2
(-475 1000);
DISPLAY 0.680851 (-475 1000);
DISPLAY INVISIBLE (-475 1000);
FORCEPROP 2 LASTPIN (-575 925) $PN 1
J 0
(-565 935);
DISPLAY 0.808511 (-565 935);
FORCEPROP 2 LASTPIN (-725 925) $PN 2
J 2
(-735 935);
DISPLAY 0.808511 (-735 935);
FORCEPROP 2 LAST VALUE DIFF BUS_0.22UF
J 2
(-800 925);
DISPLAY 0.553191 (-800 925);
FORCEPROP 2 LAST TOLERANCE 20%
J 2
(-725 975);
DISPLAY 0.553191 (-725 975);
DISPLAY INVISIBLE (-725 975);
FORCEPROP 2 LAST PACK_TYPE C0201
J 2
(-825 975);
DISPLAY 0.553191 (-825 975);
DISPLAY INVISIBLE (-825 975);
FORCEPROP 1 LAST MATERIAL X6S
J 2
(-641 1004);
DISPLAY 0.574468 (-641 1004);
PAINT GREEN (-641 1004);
DISPLAY INVISIBLE (-641 1004);
FORCEPROP 2 LAST VOLTAGE 6.3V
J 2
(-1000 975);
DISPLAY 0.553191 (-1000 975);
DISPLAY INVISIBLE (-1000 975);
FORCEPROP 1 LAST CDS_LMAN_SYM_OUTLINE -25,50,25,-50
J 2
(-650 925);
DISPLAY 0.468085 (-650 925);
PAINT GREEN (-650 925);
DISPLAY INVISIBLE (-650 925);
FORCEPROP 2 LAST CDS_LIB pure_quanta
J 2
(-650 925);
DISPLAY INVISIBLE (-650 925);
FORCEPROP 1 LAST PIN_NAMES_ROTATE TRUE
J 2
(-650 925);
DISPLAY 0.489362 (-650 925);
PAINT GREEN (-650 925);
DISPLAY INVISIBLE (-650 925);
FORCEPROP 1 LAST PART_NUMBER SP_CH4221MEE01
J 2
(-766 1013);
DISPLAY 0.574468 (-766 1013);
PAINT GREEN (-766 1013);
DISPLAY INVISIBLE (-766 1013);
FORCEPROP 1 LAST LOCATION C861
J 0
(-400 1000);
DISPLAY 1.021277 (-400 1000);
DISPLAY INVISIBLE (-400 1000);
FORCEPROP 1 LAST PATH I29
J 2
(-650 925);
DISPLAY 0.723404 (-650 925);
DISPLAY INVISIBLE (-650 925);
FORCEADD OFFPAGE..1
(-2575 3575);
FORCEPROP 2 LAST $XR0 25 
J 0
(-2796 3575);
DISPLAY 0.638298 (-2796 3575);
PAINT MONO (-2796 3575);
FORCEPROP 2 LAST CDS_LIB standard
J 0
(-2575 3575);
DISPLAY INVISIBLE (-2575 3575);
FORCEPROP 1 LAST OFFPAGE TRUE
J 0
(-2250 3450);
DISPLAY 0.872340 (-2250 3450);
DISPLAY INVISIBLE (-2250 3450);
FORCEPROP 1 LAST COMMENT_BODY TRUE
J 0
(-2450 3475);
DISPLAY 0.872340 (-2450 3475);
PAINT GREEN (-2450 3475);
DISPLAY INVISIBLE (-2450 3475);
FORCEPROP 2 LAST PATH I3
J 0
(-2825 3625);
DISPLAY 1.021277 (-2825 3625);
DISPLAY INVISIBLE (-2825 3625);
FORCEADD Q_CAP_DIFFBUS..2
R 2
(-650 975);
FORCEPROP 1 LAST LOCATION C860
J 2
(-416 992);
DISPLAY 0.723404 (-416 992);
PAINT GREEN (-416 992);
FORCEPROP 2 LAST $SEC 1
J 2
(-475 1050);
DISPLAY 0.680851 (-475 1050);
PAINT MONO (-475 1050);
DISPLAY INVISIBLE (-475 1050);
FORCEPROP 2 LAST CDS_SEC 1
J 2
(-475 1050);
DISPLAY 0.680851 (-475 1050);
DISPLAY INVISIBLE (-475 1050);
FORCEPROP 2 LASTPIN (-575 975) $PN 1
J 0
(-565 985);
DISPLAY 0.808511 (-565 985);
FORCEPROP 2 LASTPIN (-725 975) $PN 2
J 2
(-735 985);
DISPLAY 0.808511 (-735 985);
FORCEPROP 2 LAST VALUE DIFF BUS_0.22UF
J 2
(-800 975);
DISPLAY 0.553191 (-800 975);
FORCEPROP 2 LAST TOLERANCE 20%
J 2
(-725 1025);
DISPLAY 0.553191 (-725 1025);
DISPLAY INVISIBLE (-725 1025);
FORCEPROP 2 LAST PACK_TYPE C0201
J 2
(-825 1025);
DISPLAY 0.553191 (-825 1025);
DISPLAY INVISIBLE (-825 1025);
FORCEPROP 1 LAST MATERIAL X6S
J 2
(-641 1054);
DISPLAY 0.574468 (-641 1054);
PAINT GREEN (-641 1054);
DISPLAY INVISIBLE (-641 1054);
FORCEPROP 2 LAST VOLTAGE 6.3V
J 2
(-1000 1025);
DISPLAY 0.553191 (-1000 1025);
DISPLAY INVISIBLE (-1000 1025);
FORCEPROP 1 LAST CDS_LMAN_SYM_OUTLINE -25,50,25,-50
J 2
(-650 975);
DISPLAY 0.468085 (-650 975);
PAINT GREEN (-650 975);
DISPLAY INVISIBLE (-650 975);
FORCEPROP 2 LAST CDS_LIB pure_quanta
J 2
(-650 975);
DISPLAY INVISIBLE (-650 975);
FORCEPROP 1 LAST PIN_NAMES_ROTATE TRUE
J 2
(-650 975);
DISPLAY 0.489362 (-650 975);
PAINT GREEN (-650 975);
DISPLAY INVISIBLE (-650 975);
FORCEPROP 1 LAST PART_NUMBER SP_CH4221MEE01
J 2
(-766 1063);
DISPLAY 0.574468 (-766 1063);
PAINT GREEN (-766 1063);
DISPLAY INVISIBLE (-766 1063);
FORCEPROP 1 LAST LOCATION C860
J 0
(-400 1050);
DISPLAY 1.021277 (-400 1050);
DISPLAY INVISIBLE (-400 1050);
FORCEPROP 1 LAST PATH I30
J 2
(-650 975);
DISPLAY 0.723404 (-650 975);
DISPLAY INVISIBLE (-650 975);
FORCEADD TAP..1
(-100 175);
FORCEPROP 3 LASTPIN (-150 175) SIG_NAME P5E_CPU0_P2_TX_C_DN<0>
J 0
(-140 185);
DISPLAY 0.659574 (-140 185);
PAINT MONO (-140 185);
DISPLAY INVISIBLE (-140 185);
FORCEPROP 1 LASTPIN (-150 175) BN 0
J 0
(-162 183);
DISPLAY 0.680851 (-162 183);
PAINT GREEN (-162 183);
FORCEPROP 2 LAST CDS_LIB standard
J 0
(-100 175);
DISPLAY INVISIBLE (-100 175);
FORCEPROP 1 LAST BODY_TYPE PLUMBING
J 0
(-100 225);
DISPLAY 0.872340 (-100 225);
PAINT GREEN (-100 225);
DISPLAY INVISIBLE (-100 225);
FORCEPROP 1 LAST HDL_TAP TRUE
J 0
(225 50);
DISPLAY 0.872340 (225 50);
DISPLAY INVISIBLE (225 50);
FORCEPROP 1 LAST PATH I31
J 0
(-102 175);
DISPLAY 0.872340 (-102 175);
PAINT GREEN (-102 175);
DISPLAY INVISIBLE (-102 175);
FORCEADD TAP..1
(-100 375);
FORCEPROP 3 LASTPIN (-150 375) SIG_NAME P5E_CPU0_P2_TX_C_DN<1>
J 0
(-140 385);
DISPLAY 0.659574 (-140 385);
PAINT MONO (-140 385);
DISPLAY INVISIBLE (-140 385);
FORCEPROP 1 LASTPIN (-150 375) BN 1
J 0
(-162 383);
DISPLAY 0.680851 (-162 383);
PAINT GREEN (-162 383);
FORCEPROP 2 LAST CDS_LIB standard
J 0
(-100 375);
DISPLAY INVISIBLE (-100 375);
FORCEPROP 1 LAST BODY_TYPE PLUMBING
J 0
(-100 425);
DISPLAY 0.872340 (-100 425);
PAINT GREEN (-100 425);
DISPLAY INVISIBLE (-100 425);
FORCEPROP 1 LAST HDL_TAP TRUE
J 0
(225 250);
DISPLAY 0.872340 (225 250);
DISPLAY INVISIBLE (225 250);
FORCEPROP 1 LAST PATH I32
J 0
(-102 375);
DISPLAY 0.872340 (-102 375);
PAINT GREEN (-102 375);
DISPLAY INVISIBLE (-102 375);
FORCEADD TAP..1
(-100 575);
FORCEPROP 3 LASTPIN (-150 575) SIG_NAME P5E_CPU0_P2_TX_C_DN<2>
J 0
(-140 585);
DISPLAY 0.659574 (-140 585);
PAINT MONO (-140 585);
DISPLAY INVISIBLE (-140 585);
FORCEPROP 1 LASTPIN (-150 575) BN 2
J 0
(-162 583);
DISPLAY 0.680851 (-162 583);
PAINT GREEN (-162 583);
FORCEPROP 2 LAST CDS_LIB standard
J 0
(-100 575);
DISPLAY INVISIBLE (-100 575);
FORCEPROP 1 LAST BODY_TYPE PLUMBING
J 0
(-100 625);
DISPLAY 0.872340 (-100 625);
PAINT GREEN (-100 625);
DISPLAY INVISIBLE (-100 625);
FORCEPROP 1 LAST HDL_TAP TRUE
J 0
(225 450);
DISPLAY 0.872340 (225 450);
DISPLAY INVISIBLE (225 450);
FORCEPROP 1 LAST PATH I33
J 0
(-102 575);
DISPLAY 0.872340 (-102 575);
PAINT GREEN (-102 575);
DISPLAY INVISIBLE (-102 575);
FORCEADD TAP..1
(-100 775);
FORCEPROP 3 LASTPIN (-150 775) SIG_NAME P5E_CPU0_P2_TX_C_DN<3>
J 0
(-140 785);
DISPLAY 0.659574 (-140 785);
PAINT MONO (-140 785);
DISPLAY INVISIBLE (-140 785);
FORCEPROP 1 LASTPIN (-150 775) BN 3
J 0
(-162 783);
DISPLAY 0.680851 (-162 783);
PAINT GREEN (-162 783);
FORCEPROP 2 LAST CDS_LIB standard
J 0
(-100 775);
DISPLAY INVISIBLE (-100 775);
FORCEPROP 1 LAST BODY_TYPE PLUMBING
J 0
(-100 825);
DISPLAY 0.872340 (-100 825);
PAINT GREEN (-100 825);
DISPLAY INVISIBLE (-100 825);
FORCEPROP 1 LAST HDL_TAP TRUE
J 0
(225 650);
DISPLAY 0.872340 (225 650);
DISPLAY INVISIBLE (225 650);
FORCEPROP 1 LAST PATH I34
J 0
(-102 775);
DISPLAY 0.872340 (-102 775);
PAINT GREEN (-102 775);
DISPLAY INVISIBLE (-102 775);
FORCEADD TAP..1
(-100 975);
FORCEPROP 3 LASTPIN (-150 975) SIG_NAME P5E_CPU0_P2_TX_C_DN<4>
J 0
(-140 985);
DISPLAY 0.659574 (-140 985);
PAINT MONO (-140 985);
DISPLAY INVISIBLE (-140 985);
FORCEPROP 1 LASTPIN (-150 975) BN 4
J 0
(-162 983);
DISPLAY 0.680851 (-162 983);
PAINT GREEN (-162 983);
FORCEPROP 2 LAST CDS_LIB standard
J 0
(-100 975);
DISPLAY INVISIBLE (-100 975);
FORCEPROP 1 LAST BODY_TYPE PLUMBING
J 0
(-100 1025);
DISPLAY 0.872340 (-100 1025);
PAINT GREEN (-100 1025);
DISPLAY INVISIBLE (-100 1025);
FORCEPROP 1 LAST HDL_TAP TRUE
J 0
(225 850);
DISPLAY 0.872340 (225 850);
DISPLAY INVISIBLE (225 850);
FORCEPROP 1 LAST PATH I35
J 0
(-102 975);
DISPLAY 0.872340 (-102 975);
PAINT GREEN (-102 975);
DISPLAY INVISIBLE (-102 975);
FORCEADD Q_CAP_DIFFBUS..2
R 2
(-650 1125);
FORCEPROP 1 LAST LOCATION C859
J 2
(-416 1142);
DISPLAY 0.723404 (-416 1142);
PAINT GREEN (-416 1142);
FORCEPROP 2 LAST $SEC 1
J 2
(-475 1200);
DISPLAY 0.680851 (-475 1200);
PAINT MONO (-475 1200);
DISPLAY INVISIBLE (-475 1200);
FORCEPROP 2 LAST CDS_SEC 1
J 2
(-475 1200);
DISPLAY 0.680851 (-475 1200);
DISPLAY INVISIBLE (-475 1200);
FORCEPROP 2 LASTPIN (-575 1125) $PN 1
J 0
(-565 1135);
DISPLAY 0.808511 (-565 1135);
FORCEPROP 2 LASTPIN (-725 1125) $PN 2
J 2
(-735 1135);
DISPLAY 0.808511 (-735 1135);
FORCEPROP 2 LAST VALUE DIFF BUS_0.22UF
J 2
(-800 1125);
DISPLAY 0.553191 (-800 1125);
FORCEPROP 2 LAST TOLERANCE 20%
J 2
(-725 1175);
DISPLAY 0.553191 (-725 1175);
DISPLAY INVISIBLE (-725 1175);
FORCEPROP 2 LAST PACK_TYPE C0201
J 2
(-825 1175);
DISPLAY 0.553191 (-825 1175);
DISPLAY INVISIBLE (-825 1175);
FORCEPROP 1 LAST MATERIAL X6S
J 2
(-641 1204);
DISPLAY 0.574468 (-641 1204);
PAINT GREEN (-641 1204);
DISPLAY INVISIBLE (-641 1204);
FORCEPROP 2 LAST VOLTAGE 6.3V
J 2
(-1000 1175);
DISPLAY 0.553191 (-1000 1175);
DISPLAY INVISIBLE (-1000 1175);
FORCEPROP 1 LAST CDS_LMAN_SYM_OUTLINE -25,50,25,-50
J 2
(-650 1125);
DISPLAY 0.468085 (-650 1125);
PAINT GREEN (-650 1125);
DISPLAY INVISIBLE (-650 1125);
FORCEPROP 2 LAST CDS_LIB pure_quanta
J 2
(-650 1125);
DISPLAY INVISIBLE (-650 1125);
FORCEPROP 1 LAST PIN_NAMES_ROTATE TRUE
J 2
(-650 1125);
DISPLAY 0.489362 (-650 1125);
PAINT GREEN (-650 1125);
DISPLAY INVISIBLE (-650 1125);
FORCEPROP 1 LAST PART_NUMBER SP_CH4221MEE01
J 2
(-766 1213);
DISPLAY 0.574468 (-766 1213);
PAINT GREEN (-766 1213);
DISPLAY INVISIBLE (-766 1213);
FORCEPROP 1 LAST LOCATION C859
J 0
(-400 1200);
DISPLAY 1.021277 (-400 1200);
DISPLAY INVISIBLE (-400 1200);
FORCEPROP 1 LAST PATH I36
J 2
(-650 1125);
DISPLAY 0.723404 (-650 1125);
DISPLAY INVISIBLE (-650 1125);
FORCEADD Q_CAP_DIFFBUS..2
R 2
(-650 1175);
FORCEPROP 1 LAST LOCATION C858
J 2
(-416 1192);
DISPLAY 0.723404 (-416 1192);
PAINT GREEN (-416 1192);
FORCEPROP 2 LAST $SEC 1
J 2
(-475 1250);
DISPLAY 0.680851 (-475 1250);
PAINT MONO (-475 1250);
DISPLAY INVISIBLE (-475 1250);
FORCEPROP 2 LAST CDS_SEC 1
J 2
(-475 1250);
DISPLAY 0.680851 (-475 1250);
DISPLAY INVISIBLE (-475 1250);
FORCEPROP 2 LASTPIN (-575 1175) $PN 1
J 0
(-565 1185);
DISPLAY 0.808511 (-565 1185);
FORCEPROP 2 LASTPIN (-725 1175) $PN 2
J 2
(-735 1185);
DISPLAY 0.808511 (-735 1185);
FORCEPROP 2 LAST VALUE DIFF BUS_0.22UF
J 2
(-800 1175);
DISPLAY 0.553191 (-800 1175);
FORCEPROP 2 LAST TOLERANCE 20%
J 2
(-725 1225);
DISPLAY 0.553191 (-725 1225);
DISPLAY INVISIBLE (-725 1225);
FORCEPROP 2 LAST PACK_TYPE C0201
J 2
(-825 1225);
DISPLAY 0.553191 (-825 1225);
DISPLAY INVISIBLE (-825 1225);
FORCEPROP 1 LAST MATERIAL X6S
J 2
(-641 1254);
DISPLAY 0.574468 (-641 1254);
PAINT GREEN (-641 1254);
DISPLAY INVISIBLE (-641 1254);
FORCEPROP 2 LAST VOLTAGE 6.3V
J 2
(-1000 1225);
DISPLAY 0.553191 (-1000 1225);
DISPLAY INVISIBLE (-1000 1225);
FORCEPROP 1 LAST CDS_LMAN_SYM_OUTLINE -25,50,25,-50
J 2
(-650 1175);
DISPLAY 0.468085 (-650 1175);
PAINT GREEN (-650 1175);
DISPLAY INVISIBLE (-650 1175);
FORCEPROP 2 LAST CDS_LIB pure_quanta
J 2
(-650 1175);
DISPLAY INVISIBLE (-650 1175);
FORCEPROP 1 LAST PIN_NAMES_ROTATE TRUE
J 2
(-650 1175);
DISPLAY 0.489362 (-650 1175);
PAINT GREEN (-650 1175);
DISPLAY INVISIBLE (-650 1175);
FORCEPROP 1 LAST PART_NUMBER SP_CH4221MEE01
J 2
(-766 1263);
DISPLAY 0.574468 (-766 1263);
PAINT GREEN (-766 1263);
DISPLAY INVISIBLE (-766 1263);
FORCEPROP 1 LAST LOCATION C858
J 0
(-400 1250);
DISPLAY 1.021277 (-400 1250);
DISPLAY INVISIBLE (-400 1250);
FORCEPROP 1 LAST PATH I37
J 2
(-650 1175);
DISPLAY 0.723404 (-650 1175);
DISPLAY INVISIBLE (-650 1175);
FORCEADD Q_CAP_DIFFBUS..2
R 2
(-650 1325);
FORCEPROP 1 LAST LOCATION C857
J 2
(-416 1342);
DISPLAY 0.723404 (-416 1342);
PAINT GREEN (-416 1342);
FORCEPROP 2 LAST $SEC 1
J 2
(-475 1400);
DISPLAY 0.680851 (-475 1400);
PAINT MONO (-475 1400);
DISPLAY INVISIBLE (-475 1400);
FORCEPROP 2 LAST CDS_SEC 1
J 2
(-475 1400);
DISPLAY 0.680851 (-475 1400);
DISPLAY INVISIBLE (-475 1400);
FORCEPROP 2 LASTPIN (-575 1325) $PN 1
J 0
(-565 1335);
DISPLAY 0.808511 (-565 1335);
FORCEPROP 2 LASTPIN (-725 1325) $PN 2
J 2
(-735 1335);
DISPLAY 0.808511 (-735 1335);
FORCEPROP 2 LAST VALUE DIFF BUS_0.22UF
J 2
(-800 1325);
DISPLAY 0.553191 (-800 1325);
FORCEPROP 2 LAST TOLERANCE 20%
J 2
(-725 1375);
DISPLAY 0.553191 (-725 1375);
DISPLAY INVISIBLE (-725 1375);
FORCEPROP 2 LAST PACK_TYPE C0201
J 2
(-825 1375);
DISPLAY 0.553191 (-825 1375);
DISPLAY INVISIBLE (-825 1375);
FORCEPROP 1 LAST MATERIAL X6S
J 2
(-641 1404);
DISPLAY 0.574468 (-641 1404);
PAINT GREEN (-641 1404);
DISPLAY INVISIBLE (-641 1404);
FORCEPROP 2 LAST VOLTAGE 6.3V
J 2
(-1000 1375);
DISPLAY 0.553191 (-1000 1375);
DISPLAY INVISIBLE (-1000 1375);
FORCEPROP 1 LAST CDS_LMAN_SYM_OUTLINE -25,50,25,-50
J 2
(-650 1325);
DISPLAY 0.468085 (-650 1325);
PAINT GREEN (-650 1325);
DISPLAY INVISIBLE (-650 1325);
FORCEPROP 2 LAST CDS_LIB pure_quanta
J 2
(-650 1325);
DISPLAY INVISIBLE (-650 1325);
FORCEPROP 1 LAST PIN_NAMES_ROTATE TRUE
J 2
(-650 1325);
DISPLAY 0.489362 (-650 1325);
PAINT GREEN (-650 1325);
DISPLAY INVISIBLE (-650 1325);
FORCEPROP 1 LAST PART_NUMBER SP_CH4221MEE01
J 2
(-766 1413);
DISPLAY 0.574468 (-766 1413);
PAINT GREEN (-766 1413);
DISPLAY INVISIBLE (-766 1413);
FORCEPROP 1 LAST LOCATION C857
J 0
(-400 1400);
DISPLAY 1.021277 (-400 1400);
DISPLAY INVISIBLE (-400 1400);
FORCEPROP 1 LAST PATH I38
J 2
(-650 1325);
DISPLAY 0.723404 (-650 1325);
DISPLAY INVISIBLE (-650 1325);
FORCEADD Q_CAP_DIFFBUS..2
R 2
(-650 1375);
FORCEPROP 1 LAST LOCATION C856
J 2
(-416 1392);
DISPLAY 0.723404 (-416 1392);
PAINT GREEN (-416 1392);
FORCEPROP 2 LAST $SEC 1
J 2
(-475 1450);
DISPLAY 0.680851 (-475 1450);
PAINT MONO (-475 1450);
DISPLAY INVISIBLE (-475 1450);
FORCEPROP 2 LAST CDS_SEC 1
J 2
(-475 1450);
DISPLAY 0.680851 (-475 1450);
DISPLAY INVISIBLE (-475 1450);
FORCEPROP 2 LASTPIN (-575 1375) $PN 1
J 0
(-565 1385);
DISPLAY 0.808511 (-565 1385);
FORCEPROP 2 LASTPIN (-725 1375) $PN 2
J 2
(-735 1385);
DISPLAY 0.808511 (-735 1385);
FORCEPROP 2 LAST VALUE DIFF BUS_0.22UF
J 2
(-800 1375);
DISPLAY 0.553191 (-800 1375);
FORCEPROP 2 LAST TOLERANCE 20%
J 2
(-725 1425);
DISPLAY 0.553191 (-725 1425);
DISPLAY INVISIBLE (-725 1425);
FORCEPROP 2 LAST PACK_TYPE C0201
J 2
(-825 1425);
DISPLAY 0.553191 (-825 1425);
DISPLAY INVISIBLE (-825 1425);
FORCEPROP 1 LAST MATERIAL X6S
J 2
(-641 1454);
DISPLAY 0.574468 (-641 1454);
PAINT GREEN (-641 1454);
DISPLAY INVISIBLE (-641 1454);
FORCEPROP 2 LAST VOLTAGE 6.3V
J 2
(-1000 1425);
DISPLAY 0.553191 (-1000 1425);
DISPLAY INVISIBLE (-1000 1425);
FORCEPROP 1 LAST CDS_LMAN_SYM_OUTLINE -25,50,25,-50
J 2
(-650 1375);
DISPLAY 0.468085 (-650 1375);
PAINT GREEN (-650 1375);
DISPLAY INVISIBLE (-650 1375);
FORCEPROP 2 LAST CDS_LIB pure_quanta
J 2
(-650 1375);
DISPLAY INVISIBLE (-650 1375);
FORCEPROP 1 LAST PIN_NAMES_ROTATE TRUE
J 2
(-650 1375);
DISPLAY 0.489362 (-650 1375);
PAINT GREEN (-650 1375);
DISPLAY INVISIBLE (-650 1375);
FORCEPROP 1 LAST PART_NUMBER SP_CH4221MEE01
J 2
(-766 1463);
DISPLAY 0.574468 (-766 1463);
PAINT GREEN (-766 1463);
DISPLAY INVISIBLE (-766 1463);
FORCEPROP 1 LAST LOCATION C856
J 0
(-400 1450);
DISPLAY 1.021277 (-400 1450);
DISPLAY INVISIBLE (-400 1450);
FORCEPROP 1 LAST PATH I39
J 2
(-650 1375);
DISPLAY 0.723404 (-650 1375);
DISPLAY INVISIBLE (-650 1375);
FORCEADD OFFPAGE..1
(-2575 3525);
FORCEPROP 2 LAST $XR0 25 
J 0
(-2796 3525);
DISPLAY 0.638298 (-2796 3525);
PAINT MONO (-2796 3525);
FORCEPROP 2 LAST CDS_LIB standard
J 0
(-2575 3525);
DISPLAY INVISIBLE (-2575 3525);
FORCEPROP 1 LAST OFFPAGE TRUE
J 0
(-2250 3400);
DISPLAY 0.872340 (-2250 3400);
DISPLAY INVISIBLE (-2250 3400);
FORCEPROP 1 LAST COMMENT_BODY TRUE
J 0
(-2450 3425);
DISPLAY 0.872340 (-2450 3425);
PAINT GREEN (-2450 3425);
DISPLAY INVISIBLE (-2450 3425);
FORCEPROP 2 LAST PATH I4
J 0
(-2825 3575);
DISPLAY 1.021277 (-2825 3575);
DISPLAY INVISIBLE (-2825 3575);
FORCEADD Q_CAP_DIFFBUS..2
R 2
(-650 1525);
FORCEPROP 1 LAST LOCATION C855
J 2
(-416 1542);
DISPLAY 0.723404 (-416 1542);
PAINT GREEN (-416 1542);
FORCEPROP 2 LAST $SEC 1
J 2
(-475 1600);
DISPLAY 0.680851 (-475 1600);
PAINT MONO (-475 1600);
DISPLAY INVISIBLE (-475 1600);
FORCEPROP 2 LAST CDS_SEC 1
J 2
(-475 1600);
DISPLAY 0.680851 (-475 1600);
DISPLAY INVISIBLE (-475 1600);
FORCEPROP 2 LASTPIN (-575 1525) $PN 1
J 0
(-565 1535);
DISPLAY 0.808511 (-565 1535);
FORCEPROP 2 LASTPIN (-725 1525) $PN 2
J 2
(-735 1535);
DISPLAY 0.808511 (-735 1535);
FORCEPROP 2 LAST VALUE DIFF BUS_0.22UF
J 2
(-800 1525);
DISPLAY 0.553191 (-800 1525);
FORCEPROP 2 LAST TOLERANCE 20%
J 2
(-725 1575);
DISPLAY 0.553191 (-725 1575);
DISPLAY INVISIBLE (-725 1575);
FORCEPROP 2 LAST PACK_TYPE C0201
J 2
(-825 1575);
DISPLAY 0.553191 (-825 1575);
DISPLAY INVISIBLE (-825 1575);
FORCEPROP 1 LAST MATERIAL X6S
J 2
(-641 1604);
DISPLAY 0.574468 (-641 1604);
PAINT GREEN (-641 1604);
DISPLAY INVISIBLE (-641 1604);
FORCEPROP 2 LAST VOLTAGE 6.3V
J 2
(-1000 1575);
DISPLAY 0.553191 (-1000 1575);
DISPLAY INVISIBLE (-1000 1575);
FORCEPROP 1 LAST CDS_LMAN_SYM_OUTLINE -25,50,25,-50
J 2
(-650 1525);
DISPLAY 0.468085 (-650 1525);
PAINT GREEN (-650 1525);
DISPLAY INVISIBLE (-650 1525);
FORCEPROP 2 LAST CDS_LIB pure_quanta
J 2
(-650 1525);
DISPLAY INVISIBLE (-650 1525);
FORCEPROP 1 LAST PIN_NAMES_ROTATE TRUE
J 2
(-650 1525);
DISPLAY 0.489362 (-650 1525);
PAINT GREEN (-650 1525);
DISPLAY INVISIBLE (-650 1525);
FORCEPROP 1 LAST PART_NUMBER SP_CH4221MEE01
J 2
(-766 1613);
DISPLAY 0.574468 (-766 1613);
PAINT GREEN (-766 1613);
DISPLAY INVISIBLE (-766 1613);
FORCEPROP 1 LAST LOCATION C855
J 0
(-400 1600);
DISPLAY 1.021277 (-400 1600);
DISPLAY INVISIBLE (-400 1600);
FORCEPROP 1 LAST PATH I40
J 2
(-650 1525);
DISPLAY 0.723404 (-650 1525);
DISPLAY INVISIBLE (-650 1525);
FORCEADD Q_CAP_DIFFBUS..2
R 2
(-650 1575);
FORCEPROP 1 LAST LOCATION C854
J 2
(-416 1592);
DISPLAY 0.723404 (-416 1592);
PAINT GREEN (-416 1592);
FORCEPROP 2 LAST $SEC 1
J 2
(-475 1650);
DISPLAY 0.680851 (-475 1650);
PAINT MONO (-475 1650);
DISPLAY INVISIBLE (-475 1650);
FORCEPROP 2 LAST CDS_SEC 1
J 2
(-475 1650);
DISPLAY 0.680851 (-475 1650);
DISPLAY INVISIBLE (-475 1650);
FORCEPROP 2 LASTPIN (-575 1575) $PN 1
J 0
(-565 1585);
DISPLAY 0.808511 (-565 1585);
FORCEPROP 2 LASTPIN (-725 1575) $PN 2
J 2
(-735 1585);
DISPLAY 0.808511 (-735 1585);
FORCEPROP 2 LAST VALUE DIFF BUS_0.22UF
J 2
(-800 1575);
DISPLAY 0.553191 (-800 1575);
FORCEPROP 2 LAST TOLERANCE 20%
J 2
(-725 1625);
DISPLAY 0.553191 (-725 1625);
DISPLAY INVISIBLE (-725 1625);
FORCEPROP 2 LAST PACK_TYPE C0201
J 2
(-825 1625);
DISPLAY 0.553191 (-825 1625);
DISPLAY INVISIBLE (-825 1625);
FORCEPROP 1 LAST MATERIAL X6S
J 2
(-641 1654);
DISPLAY 0.574468 (-641 1654);
PAINT GREEN (-641 1654);
DISPLAY INVISIBLE (-641 1654);
FORCEPROP 2 LAST VOLTAGE 6.3V
J 2
(-1000 1625);
DISPLAY 0.553191 (-1000 1625);
DISPLAY INVISIBLE (-1000 1625);
FORCEPROP 2 LAST CDS_LIB pure_quanta
J 2
(-650 1575);
DISPLAY INVISIBLE (-650 1575);
FORCEPROP 1 LAST CDS_LMAN_SYM_OUTLINE -25,50,25,-50
J 2
(-650 1575);
DISPLAY 0.468085 (-650 1575);
PAINT GREEN (-650 1575);
DISPLAY INVISIBLE (-650 1575);
FORCEPROP 1 LAST PIN_NAMES_ROTATE TRUE
J 2
(-650 1575);
DISPLAY 0.489362 (-650 1575);
PAINT GREEN (-650 1575);
DISPLAY INVISIBLE (-650 1575);
FORCEPROP 1 LAST PART_NUMBER SP_CH4221MEE01
J 2
(-766 1663);
DISPLAY 0.574468 (-766 1663);
PAINT GREEN (-766 1663);
DISPLAY INVISIBLE (-766 1663);
FORCEPROP 1 LAST LOCATION C854
J 0
(-400 1650);
DISPLAY 1.021277 (-400 1650);
DISPLAY INVISIBLE (-400 1650);
FORCEPROP 1 LAST PATH I41
J 2
(-650 1575);
DISPLAY 0.723404 (-650 1575);
DISPLAY INVISIBLE (-650 1575);
FORCEADD TAP..1
(-100 1375);
FORCEPROP 3 LASTPIN (-150 1375) SIG_NAME P5E_CPU0_P2_TX_C_DN<6>
J 0
(-140 1385);
DISPLAY 0.659574 (-140 1385);
PAINT MONO (-140 1385);
DISPLAY INVISIBLE (-140 1385);
FORCEPROP 1 LASTPIN (-150 1375) BN 6
J 0
(-162 1383);
DISPLAY 0.680851 (-162 1383);
PAINT GREEN (-162 1383);
FORCEPROP 2 LAST CDS_LIB standard
J 0
(-100 1375);
DISPLAY INVISIBLE (-100 1375);
FORCEPROP 1 LAST BODY_TYPE PLUMBING
J 0
(-100 1425);
DISPLAY 0.872340 (-100 1425);
PAINT GREEN (-100 1425);
DISPLAY INVISIBLE (-100 1425);
FORCEPROP 1 LAST HDL_TAP TRUE
J 0
(225 1250);
DISPLAY 0.872340 (225 1250);
DISPLAY INVISIBLE (225 1250);
FORCEPROP 1 LAST PATH I42
J 0
(-102 1375);
DISPLAY 0.872340 (-102 1375);
PAINT GREEN (-102 1375);
DISPLAY INVISIBLE (-102 1375);
FORCEADD TAP..1
(-100 1175);
FORCEPROP 3 LASTPIN (-150 1175) SIG_NAME P5E_CPU0_P2_TX_C_DN<5>
J 0
(-140 1185);
DISPLAY 0.659574 (-140 1185);
PAINT MONO (-140 1185);
DISPLAY INVISIBLE (-140 1185);
FORCEPROP 1 LASTPIN (-150 1175) BN 5
J 0
(-162 1183);
DISPLAY 0.680851 (-162 1183);
PAINT GREEN (-162 1183);
FORCEPROP 2 LAST CDS_LIB standard
J 0
(-100 1175);
DISPLAY INVISIBLE (-100 1175);
FORCEPROP 1 LAST BODY_TYPE PLUMBING
J 0
(-100 1225);
DISPLAY 0.872340 (-100 1225);
PAINT GREEN (-100 1225);
DISPLAY INVISIBLE (-100 1225);
FORCEPROP 1 LAST HDL_TAP TRUE
J 0
(225 1050);
DISPLAY 0.872340 (225 1050);
DISPLAY INVISIBLE (225 1050);
FORCEPROP 1 LAST PATH I43
J 0
(-102 1175);
DISPLAY 0.872340 (-102 1175);
PAINT GREEN (-102 1175);
DISPLAY INVISIBLE (-102 1175);
FORCEADD TAP..1
(-100 1575);
FORCEPROP 3 LASTPIN (-150 1575) SIG_NAME P5E_CPU0_P2_TX_C_DN<7>
J 0
(-140 1585);
DISPLAY 0.659574 (-140 1585);
PAINT MONO (-140 1585);
DISPLAY INVISIBLE (-140 1585);
FORCEPROP 1 LASTPIN (-150 1575) BN 7
J 0
(-162 1583);
DISPLAY 0.680851 (-162 1583);
PAINT GREEN (-162 1583);
FORCEPROP 2 LAST CDS_LIB standard
J 0
(-100 1575);
DISPLAY INVISIBLE (-100 1575);
FORCEPROP 1 LAST BODY_TYPE PLUMBING
J 0
(-100 1625);
DISPLAY 0.872340 (-100 1625);
PAINT GREEN (-100 1625);
DISPLAY INVISIBLE (-100 1625);
FORCEPROP 1 LAST HDL_TAP TRUE
J 0
(225 1450);
DISPLAY 0.872340 (225 1450);
DISPLAY INVISIBLE (225 1450);
FORCEPROP 1 LAST PATH I44
J 0
(-102 1575);
DISPLAY 0.872340 (-102 1575);
PAINT GREEN (-102 1575);
DISPLAY INVISIBLE (-102 1575);
FORCEADD TAP..1
R 2
(-1625 2100);
FORCEPROP 3 LASTPIN (-1575 2100) SIG_NAME P5E_CPU0_P2_TX_DP<8>
J 0
(-1565 2110);
DISPLAY 0.659574 (-1565 2110);
PAINT MONO (-1565 2110);
DISPLAY INVISIBLE (-1565 2110);
FORCEPROP 1 LASTPIN (-1575 2100) BN 8
J 2
(-1563 2108);
DISPLAY 0.680851 (-1563 2108);
PAINT GREEN (-1563 2108);
FORCEPROP 2 LAST CDS_LIB standard
J 0
(-1625 2100);
DISPLAY INVISIBLE (-1625 2100);
FORCEPROP 1 LAST BODY_TYPE PLUMBING
J 2
(-1625 2150);
DISPLAY 0.872340 (-1625 2150);
PAINT GREEN (-1625 2150);
DISPLAY INVISIBLE (-1625 2150);
FORCEPROP 1 LAST HDL_TAP TRUE
J 2
(-1950 1975);
DISPLAY 0.872340 (-1950 1975);
DISPLAY INVISIBLE (-1950 1975);
FORCEPROP 1 LAST PATH I45
J 2
(-1623 2100);
DISPLAY 0.872340 (-1623 2100);
PAINT GREEN (-1623 2100);
DISPLAY INVISIBLE (-1623 2100);
FORCEADD TAP..1
R 2
(-1625 2300);
FORCEPROP 3 LASTPIN (-1575 2300) SIG_NAME P5E_CPU0_P2_TX_DP<9>
J 0
(-1565 2310);
DISPLAY 0.659574 (-1565 2310);
PAINT MONO (-1565 2310);
DISPLAY INVISIBLE (-1565 2310);
FORCEPROP 1 LASTPIN (-1575 2300) BN 9
J 2
(-1563 2308);
DISPLAY 0.680851 (-1563 2308);
PAINT GREEN (-1563 2308);
FORCEPROP 2 LAST CDS_LIB standard
J 0
(-1625 2300);
DISPLAY INVISIBLE (-1625 2300);
FORCEPROP 1 LAST BODY_TYPE PLUMBING
J 2
(-1625 2350);
DISPLAY 0.872340 (-1625 2350);
PAINT GREEN (-1625 2350);
DISPLAY INVISIBLE (-1625 2350);
FORCEPROP 1 LAST HDL_TAP TRUE
J 2
(-1950 2175);
DISPLAY 0.872340 (-1950 2175);
DISPLAY INVISIBLE (-1950 2175);
FORCEPROP 1 LAST PATH I46
J 2
(-1623 2300);
DISPLAY 0.872340 (-1623 2300);
PAINT GREEN (-1623 2300);
DISPLAY INVISIBLE (-1623 2300);
FORCEADD TAP..1
R 2
(-1625 2500);
FORCEPROP 3 LASTPIN (-1575 2500) SIG_NAME P5E_CPU0_P2_TX_DP<10>
J 0
(-1565 2510);
DISPLAY 0.659574 (-1565 2510);
PAINT MONO (-1565 2510);
DISPLAY INVISIBLE (-1565 2510);
FORCEPROP 1 LASTPIN (-1575 2500) BN 10
J 2
(-1563 2508);
DISPLAY 0.680851 (-1563 2508);
PAINT GREEN (-1563 2508);
FORCEPROP 2 LAST CDS_LIB standard
J 0
(-1625 2500);
DISPLAY INVISIBLE (-1625 2500);
FORCEPROP 1 LAST BODY_TYPE PLUMBING
J 2
(-1625 2550);
DISPLAY 0.872340 (-1625 2550);
PAINT GREEN (-1625 2550);
DISPLAY INVISIBLE (-1625 2550);
FORCEPROP 1 LAST HDL_TAP TRUE
J 2
(-1950 2375);
DISPLAY 0.872340 (-1950 2375);
DISPLAY INVISIBLE (-1950 2375);
FORCEPROP 1 LAST PATH I47
J 2
(-1623 2500);
DISPLAY 0.872340 (-1623 2500);
PAINT GREEN (-1623 2500);
DISPLAY INVISIBLE (-1623 2500);
FORCEADD TAP..1
R 2
(-1625 2700);
FORCEPROP 3 LASTPIN (-1575 2700) SIG_NAME P5E_CPU0_P2_TX_DP<11>
J 0
(-1565 2710);
DISPLAY 0.659574 (-1565 2710);
PAINT MONO (-1565 2710);
DISPLAY INVISIBLE (-1565 2710);
FORCEPROP 1 LASTPIN (-1575 2700) BN 11
J 2
(-1563 2708);
DISPLAY 0.680851 (-1563 2708);
PAINT GREEN (-1563 2708);
FORCEPROP 2 LAST CDS_LIB standard
J 0
(-1625 2700);
DISPLAY INVISIBLE (-1625 2700);
FORCEPROP 1 LAST BODY_TYPE PLUMBING
J 2
(-1625 2750);
DISPLAY 0.872340 (-1625 2750);
PAINT GREEN (-1625 2750);
DISPLAY INVISIBLE (-1625 2750);
FORCEPROP 1 LAST HDL_TAP TRUE
J 2
(-1950 2575);
DISPLAY 0.872340 (-1950 2575);
DISPLAY INVISIBLE (-1950 2575);
FORCEPROP 1 LAST PATH I48
J 2
(-1623 2700);
DISPLAY 0.872340 (-1623 2700);
PAINT GREEN (-1623 2700);
DISPLAY INVISIBLE (-1623 2700);
FORCEADD TAP..1
R 2
(-1625 2900);
FORCEPROP 3 LASTPIN (-1575 2900) SIG_NAME P5E_CPU0_P2_TX_DP<12>
J 0
(-1565 2910);
DISPLAY 0.659574 (-1565 2910);
PAINT MONO (-1565 2910);
DISPLAY INVISIBLE (-1565 2910);
FORCEPROP 1 LASTPIN (-1575 2900) BN 12
J 2
(-1563 2908);
DISPLAY 0.680851 (-1563 2908);
PAINT GREEN (-1563 2908);
FORCEPROP 2 LAST CDS_LIB standard
J 0
(-1625 2900);
DISPLAY INVISIBLE (-1625 2900);
FORCEPROP 1 LAST BODY_TYPE PLUMBING
J 2
(-1625 2950);
DISPLAY 0.872340 (-1625 2950);
PAINT GREEN (-1625 2950);
DISPLAY INVISIBLE (-1625 2950);
FORCEPROP 1 LAST HDL_TAP TRUE
J 2
(-1950 2775);
DISPLAY 0.872340 (-1950 2775);
DISPLAY INVISIBLE (-1950 2775);
FORCEPROP 1 LAST PATH I49
J 2
(-1623 2900);
DISPLAY 0.872340 (-1623 2900);
PAINT GREEN (-1623 2900);
DISPLAY INVISIBLE (-1623 2900);
FORCEADD TAP..1
R 2
(-1625 125);
FORCEPROP 3 LASTPIN (-1575 125) SIG_NAME P5E_CPU0_P2_TX_DP<0>
J 0
(-1565 135);
DISPLAY 0.659574 (-1565 135);
PAINT MONO (-1565 135);
DISPLAY INVISIBLE (-1565 135);
FORCEPROP 1 LASTPIN (-1575 125) BN 0
J 2
(-1563 133);
DISPLAY 0.680851 (-1563 133);
PAINT GREEN (-1563 133);
FORCEPROP 2 LAST CDS_LIB standard
J 0
(-1625 125);
DISPLAY INVISIBLE (-1625 125);
FORCEPROP 1 LAST BODY_TYPE PLUMBING
J 2
(-1625 175);
DISPLAY 0.872340 (-1625 175);
PAINT GREEN (-1625 175);
DISPLAY INVISIBLE (-1625 175);
FORCEPROP 1 LAST HDL_TAP TRUE
J 2
(-1950 0);
DISPLAY 0.872340 (-1950 0);
DISPLAY INVISIBLE (-1950 0);
FORCEPROP 1 LAST PATH I5
J 2
(-1623 125);
DISPLAY 0.872340 (-1623 125);
PAINT GREEN (-1623 125);
DISPLAY INVISIBLE (-1623 125);
FORCEADD TAP..1
R 2
(-1375 2150);
FORCEPROP 3 LASTPIN (-1325 2150) SIG_NAME P5E_CPU0_P2_TX_DN<8>
J 0
(-1315 2160);
DISPLAY 0.659574 (-1315 2160);
PAINT MONO (-1315 2160);
DISPLAY INVISIBLE (-1315 2160);
FORCEPROP 1 LASTPIN (-1325 2150) BN 8
J 2
(-1313 2158);
DISPLAY 0.680851 (-1313 2158);
PAINT GREEN (-1313 2158);
FORCEPROP 2 LAST CDS_LIB standard
J 0
(-1375 2150);
DISPLAY INVISIBLE (-1375 2150);
FORCEPROP 1 LAST BODY_TYPE PLUMBING
J 2
(-1375 2200);
DISPLAY 0.872340 (-1375 2200);
PAINT GREEN (-1375 2200);
DISPLAY INVISIBLE (-1375 2200);
FORCEPROP 1 LAST HDL_TAP TRUE
J 2
(-1700 2025);
DISPLAY 0.872340 (-1700 2025);
DISPLAY INVISIBLE (-1700 2025);
FORCEPROP 1 LAST PATH I50
J 2
(-1373 2150);
DISPLAY 0.872340 (-1373 2150);
PAINT GREEN (-1373 2150);
DISPLAY INVISIBLE (-1373 2150);
FORCEADD TAP..1
R 2
(-1375 2350);
FORCEPROP 3 LASTPIN (-1325 2350) SIG_NAME P5E_CPU0_P2_TX_DN<9>
J 0
(-1315 2360);
DISPLAY 0.659574 (-1315 2360);
PAINT MONO (-1315 2360);
DISPLAY INVISIBLE (-1315 2360);
FORCEPROP 1 LASTPIN (-1325 2350) BN 9
J 2
(-1313 2358);
DISPLAY 0.680851 (-1313 2358);
PAINT GREEN (-1313 2358);
FORCEPROP 2 LAST CDS_LIB standard
J 0
(-1375 2350);
DISPLAY INVISIBLE (-1375 2350);
FORCEPROP 1 LAST BODY_TYPE PLUMBING
J 2
(-1375 2400);
DISPLAY 0.872340 (-1375 2400);
PAINT GREEN (-1375 2400);
DISPLAY INVISIBLE (-1375 2400);
FORCEPROP 1 LAST HDL_TAP TRUE
J 2
(-1700 2225);
DISPLAY 0.872340 (-1700 2225);
DISPLAY INVISIBLE (-1700 2225);
FORCEPROP 1 LAST PATH I51
J 2
(-1373 2350);
DISPLAY 0.872340 (-1373 2350);
PAINT GREEN (-1373 2350);
DISPLAY INVISIBLE (-1373 2350);
FORCEADD TAP..1
R 2
(-1375 2550);
FORCEPROP 3 LASTPIN (-1325 2550) SIG_NAME P5E_CPU0_P2_TX_DN<10>
J 0
(-1315 2560);
DISPLAY 0.659574 (-1315 2560);
PAINT MONO (-1315 2560);
DISPLAY INVISIBLE (-1315 2560);
FORCEPROP 1 LASTPIN (-1325 2550) BN 10
J 2
(-1313 2558);
DISPLAY 0.680851 (-1313 2558);
PAINT GREEN (-1313 2558);
FORCEPROP 2 LAST CDS_LIB standard
J 0
(-1375 2550);
DISPLAY INVISIBLE (-1375 2550);
FORCEPROP 1 LAST BODY_TYPE PLUMBING
J 2
(-1375 2600);
DISPLAY 0.872340 (-1375 2600);
PAINT GREEN (-1375 2600);
DISPLAY INVISIBLE (-1375 2600);
FORCEPROP 1 LAST HDL_TAP TRUE
J 2
(-1700 2425);
DISPLAY 0.872340 (-1700 2425);
DISPLAY INVISIBLE (-1700 2425);
FORCEPROP 1 LAST PATH I52
J 2
(-1373 2550);
DISPLAY 0.872340 (-1373 2550);
PAINT GREEN (-1373 2550);
DISPLAY INVISIBLE (-1373 2550);
FORCEADD TAP..1
R 2
(-1375 2750);
FORCEPROP 3 LASTPIN (-1325 2750) SIG_NAME P5E_CPU0_P2_TX_DN<11>
J 0
(-1315 2760);
DISPLAY 0.659574 (-1315 2760);
PAINT MONO (-1315 2760);
DISPLAY INVISIBLE (-1315 2760);
FORCEPROP 1 LASTPIN (-1325 2750) BN 11
J 2
(-1313 2758);
DISPLAY 0.680851 (-1313 2758);
PAINT GREEN (-1313 2758);
FORCEPROP 2 LAST CDS_LIB standard
J 0
(-1375 2750);
DISPLAY INVISIBLE (-1375 2750);
FORCEPROP 1 LAST BODY_TYPE PLUMBING
J 2
(-1375 2800);
DISPLAY 0.872340 (-1375 2800);
PAINT GREEN (-1375 2800);
DISPLAY INVISIBLE (-1375 2800);
FORCEPROP 1 LAST HDL_TAP TRUE
J 2
(-1700 2625);
DISPLAY 0.872340 (-1700 2625);
DISPLAY INVISIBLE (-1700 2625);
FORCEPROP 1 LAST PATH I53
J 2
(-1373 2750);
DISPLAY 0.872340 (-1373 2750);
PAINT GREEN (-1373 2750);
DISPLAY INVISIBLE (-1373 2750);
FORCEADD TAP..1
R 2
(-1375 2950);
FORCEPROP 3 LASTPIN (-1325 2950) SIG_NAME P5E_CPU0_P2_TX_DN<12>
J 0
(-1315 2960);
DISPLAY 0.659574 (-1315 2960);
PAINT MONO (-1315 2960);
DISPLAY INVISIBLE (-1315 2960);
FORCEPROP 1 LASTPIN (-1325 2950) BN 12
J 2
(-1313 2958);
DISPLAY 0.680851 (-1313 2958);
PAINT GREEN (-1313 2958);
FORCEPROP 2 LAST CDS_LIB standard
J 0
(-1375 2950);
DISPLAY INVISIBLE (-1375 2950);
FORCEPROP 1 LAST BODY_TYPE PLUMBING
J 2
(-1375 3000);
DISPLAY 0.872340 (-1375 3000);
PAINT GREEN (-1375 3000);
DISPLAY INVISIBLE (-1375 3000);
FORCEPROP 1 LAST HDL_TAP TRUE
J 2
(-1700 2825);
DISPLAY 0.872340 (-1700 2825);
DISPLAY INVISIBLE (-1700 2825);
FORCEPROP 1 LAST PATH I54
J 2
(-1373 2950);
DISPLAY 0.872340 (-1373 2950);
PAINT GREEN (-1373 2950);
DISPLAY INVISIBLE (-1373 2950);
FORCEADD TAP..1
R 2
(-1625 3500);
FORCEPROP 3 LASTPIN (-1575 3500) SIG_NAME P5E_CPU0_P2_TX_DP<15>
J 0
(-1565 3510);
DISPLAY 0.659574 (-1565 3510);
PAINT MONO (-1565 3510);
DISPLAY INVISIBLE (-1565 3510);
FORCEPROP 1 LASTPIN (-1575 3500) BN 15
J 2
(-1563 3508);
DISPLAY 0.680851 (-1563 3508);
PAINT GREEN (-1563 3508);
FORCEPROP 2 LAST CDS_LIB standard
J 0
(-1625 3500);
DISPLAY INVISIBLE (-1625 3500);
FORCEPROP 1 LAST BODY_TYPE PLUMBING
J 2
(-1625 3550);
DISPLAY 0.872340 (-1625 3550);
PAINT GREEN (-1625 3550);
DISPLAY INVISIBLE (-1625 3550);
FORCEPROP 1 LAST HDL_TAP TRUE
J 2
(-1950 3375);
DISPLAY 0.872340 (-1950 3375);
DISPLAY INVISIBLE (-1950 3375);
FORCEPROP 1 LAST PATH I55
J 2
(-1623 3500);
DISPLAY 0.872340 (-1623 3500);
PAINT GREEN (-1623 3500);
DISPLAY INVISIBLE (-1623 3500);
FORCEADD TAP..1
R 2
(-1625 3300);
FORCEPROP 3 LASTPIN (-1575 3300) SIG_NAME P5E_CPU0_P2_TX_DP<14>
J 0
(-1565 3310);
DISPLAY 0.659574 (-1565 3310);
PAINT MONO (-1565 3310);
DISPLAY INVISIBLE (-1565 3310);
FORCEPROP 1 LASTPIN (-1575 3300) BN 14
J 2
(-1563 3308);
DISPLAY 0.680851 (-1563 3308);
PAINT GREEN (-1563 3308);
FORCEPROP 2 LAST CDS_LIB standard
J 0
(-1625 3300);
DISPLAY INVISIBLE (-1625 3300);
FORCEPROP 1 LAST BODY_TYPE PLUMBING
J 2
(-1625 3350);
DISPLAY 0.872340 (-1625 3350);
PAINT GREEN (-1625 3350);
DISPLAY INVISIBLE (-1625 3350);
FORCEPROP 1 LAST HDL_TAP TRUE
J 2
(-1950 3175);
DISPLAY 0.872340 (-1950 3175);
DISPLAY INVISIBLE (-1950 3175);
FORCEPROP 1 LAST PATH I56
J 2
(-1623 3300);
DISPLAY 0.872340 (-1623 3300);
PAINT GREEN (-1623 3300);
DISPLAY INVISIBLE (-1623 3300);
FORCEADD TAP..1
R 2
(-1625 3100);
FORCEPROP 3 LASTPIN (-1575 3100) SIG_NAME P5E_CPU0_P2_TX_DP<13>
J 0
(-1565 3110);
DISPLAY 0.659574 (-1565 3110);
PAINT MONO (-1565 3110);
DISPLAY INVISIBLE (-1565 3110);
FORCEPROP 1 LASTPIN (-1575 3100) BN 13
J 2
(-1563 3108);
DISPLAY 0.680851 (-1563 3108);
PAINT GREEN (-1563 3108);
FORCEPROP 2 LAST CDS_LIB standard
J 0
(-1625 3100);
DISPLAY INVISIBLE (-1625 3100);
FORCEPROP 1 LAST BODY_TYPE PLUMBING
J 2
(-1625 3150);
DISPLAY 0.872340 (-1625 3150);
PAINT GREEN (-1625 3150);
DISPLAY INVISIBLE (-1625 3150);
FORCEPROP 1 LAST HDL_TAP TRUE
J 2
(-1950 2975);
DISPLAY 0.872340 (-1950 2975);
DISPLAY INVISIBLE (-1950 2975);
FORCEPROP 1 LAST PATH I57
J 2
(-1623 3100);
DISPLAY 0.872340 (-1623 3100);
PAINT GREEN (-1623 3100);
DISPLAY INVISIBLE (-1623 3100);
FORCEADD TAP..1
R 2
(-1375 3150);
FORCEPROP 3 LASTPIN (-1325 3150) SIG_NAME P5E_CPU0_P2_TX_DN<13>
J 0
(-1315 3160);
DISPLAY 0.659574 (-1315 3160);
PAINT MONO (-1315 3160);
DISPLAY INVISIBLE (-1315 3160);
FORCEPROP 1 LASTPIN (-1325 3150) BN 13
J 2
(-1313 3158);
DISPLAY 0.680851 (-1313 3158);
PAINT GREEN (-1313 3158);
FORCEPROP 2 LAST CDS_LIB standard
J 0
(-1375 3150);
DISPLAY INVISIBLE (-1375 3150);
FORCEPROP 1 LAST BODY_TYPE PLUMBING
J 2
(-1375 3200);
DISPLAY 0.872340 (-1375 3200);
PAINT GREEN (-1375 3200);
DISPLAY INVISIBLE (-1375 3200);
FORCEPROP 1 LAST HDL_TAP TRUE
J 2
(-1700 3025);
DISPLAY 0.872340 (-1700 3025);
DISPLAY INVISIBLE (-1700 3025);
FORCEPROP 1 LAST PATH I58
J 2
(-1373 3150);
DISPLAY 0.872340 (-1373 3150);
PAINT GREEN (-1373 3150);
DISPLAY INVISIBLE (-1373 3150);
FORCEADD TAP..1
R 2
(-1375 3350);
FORCEPROP 3 LASTPIN (-1325 3350) SIG_NAME P5E_CPU0_P2_TX_DN<14>
J 0
(-1315 3360);
DISPLAY 0.659574 (-1315 3360);
PAINT MONO (-1315 3360);
DISPLAY INVISIBLE (-1315 3360);
FORCEPROP 1 LASTPIN (-1325 3350) BN 14
J 2
(-1313 3358);
DISPLAY 0.680851 (-1313 3358);
PAINT GREEN (-1313 3358);
FORCEPROP 2 LAST CDS_LIB standard
J 0
(-1375 3350);
DISPLAY INVISIBLE (-1375 3350);
FORCEPROP 1 LAST BODY_TYPE PLUMBING
J 2
(-1375 3400);
DISPLAY 0.872340 (-1375 3400);
PAINT GREEN (-1375 3400);
DISPLAY INVISIBLE (-1375 3400);
FORCEPROP 1 LAST HDL_TAP TRUE
J 2
(-1700 3225);
DISPLAY 0.872340 (-1700 3225);
DISPLAY INVISIBLE (-1700 3225);
FORCEPROP 1 LAST PATH I59
J 2
(-1373 3350);
DISPLAY 0.872340 (-1373 3350);
PAINT GREEN (-1373 3350);
DISPLAY INVISIBLE (-1373 3350);
FORCEADD TAP..1
R 2
(-1625 325);
FORCEPROP 3 LASTPIN (-1575 325) SIG_NAME P5E_CPU0_P2_TX_DP<1>
J 0
(-1565 335);
DISPLAY 0.659574 (-1565 335);
PAINT MONO (-1565 335);
DISPLAY INVISIBLE (-1565 335);
FORCEPROP 1 LASTPIN (-1575 325) BN 1
J 2
(-1563 333);
DISPLAY 0.680851 (-1563 333);
PAINT GREEN (-1563 333);
FORCEPROP 2 LAST CDS_LIB standard
J 0
(-1625 325);
DISPLAY INVISIBLE (-1625 325);
FORCEPROP 1 LAST BODY_TYPE PLUMBING
J 2
(-1625 375);
DISPLAY 0.872340 (-1625 375);
PAINT GREEN (-1625 375);
DISPLAY INVISIBLE (-1625 375);
FORCEPROP 1 LAST HDL_TAP TRUE
J 2
(-1950 200);
DISPLAY 0.872340 (-1950 200);
DISPLAY INVISIBLE (-1950 200);
FORCEPROP 1 LAST PATH I6
J 2
(-1623 325);
DISPLAY 0.872340 (-1623 325);
PAINT GREEN (-1623 325);
DISPLAY INVISIBLE (-1623 325);
FORCEADD TAP..1
R 2
(-1375 3550);
FORCEPROP 3 LASTPIN (-1325 3550) SIG_NAME P5E_CPU0_P2_TX_DN<15>
J 0
(-1315 3560);
DISPLAY 0.659574 (-1315 3560);
PAINT MONO (-1315 3560);
DISPLAY INVISIBLE (-1315 3560);
FORCEPROP 1 LASTPIN (-1325 3550) BN 15
J 2
(-1313 3558);
DISPLAY 0.680851 (-1313 3558);
PAINT GREEN (-1313 3558);
FORCEPROP 2 LAST CDS_LIB standard
J 0
(-1375 3550);
DISPLAY INVISIBLE (-1375 3550);
FORCEPROP 1 LAST BODY_TYPE PLUMBING
J 2
(-1375 3600);
DISPLAY 0.872340 (-1375 3600);
PAINT GREEN (-1375 3600);
DISPLAY INVISIBLE (-1375 3600);
FORCEPROP 1 LAST HDL_TAP TRUE
J 2
(-1700 3425);
DISPLAY 0.872340 (-1700 3425);
DISPLAY INVISIBLE (-1700 3425);
FORCEPROP 1 LAST PATH I60
J 2
(-1373 3550);
DISPLAY 0.872340 (-1373 3550);
PAINT GREEN (-1373 3550);
DISPLAY INVISIBLE (-1373 3550);
FORCEADD Q_CAP_DIFFBUS..2
R 2
(-650 2150);
FORCEPROP 1 LAST LOCATION C852
J 2
(-416 2167);
DISPLAY 0.723404 (-416 2167);
PAINT GREEN (-416 2167);
FORCEPROP 2 LAST $SEC 1
J 2
(-475 2225);
DISPLAY 0.680851 (-475 2225);
PAINT MONO (-475 2225);
DISPLAY INVISIBLE (-475 2225);
FORCEPROP 2 LAST CDS_SEC 1
J 2
(-475 2225);
DISPLAY 0.680851 (-475 2225);
DISPLAY INVISIBLE (-475 2225);
FORCEPROP 2 LASTPIN (-575 2150) $PN 1
J 0
(-565 2160);
DISPLAY 0.808511 (-565 2160);
FORCEPROP 2 LASTPIN (-725 2150) $PN 2
J 2
(-735 2160);
DISPLAY 0.808511 (-735 2160);
FORCEPROP 2 LAST VALUE DIFF BUS_0.22UF
J 2
(-800 2150);
DISPLAY 0.553191 (-800 2150);
FORCEPROP 2 LAST TOLERANCE 20%
J 2
(-725 2200);
DISPLAY 0.553191 (-725 2200);
DISPLAY INVISIBLE (-725 2200);
FORCEPROP 2 LAST PACK_TYPE C0201
J 2
(-825 2200);
DISPLAY 0.553191 (-825 2200);
DISPLAY INVISIBLE (-825 2200);
FORCEPROP 1 LAST MATERIAL X6S
J 2
(-641 2229);
DISPLAY 0.574468 (-641 2229);
PAINT GREEN (-641 2229);
DISPLAY INVISIBLE (-641 2229);
FORCEPROP 2 LAST VOLTAGE 6.3V
J 2
(-1000 2200);
DISPLAY 0.553191 (-1000 2200);
DISPLAY INVISIBLE (-1000 2200);
FORCEPROP 1 LAST PIN_NAMES_ROTATE TRUE
J 2
(-650 2150);
DISPLAY 0.489362 (-650 2150);
PAINT GREEN (-650 2150);
DISPLAY INVISIBLE (-650 2150);
FORCEPROP 2 LAST CDS_LIB pure_quanta
J 2
(-650 2150);
DISPLAY INVISIBLE (-650 2150);
FORCEPROP 1 LAST CDS_LMAN_SYM_OUTLINE -25,50,25,-50
J 2
(-650 2150);
DISPLAY 0.468085 (-650 2150);
PAINT GREEN (-650 2150);
DISPLAY INVISIBLE (-650 2150);
FORCEPROP 1 LAST PART_NUMBER SP_CH4221MEE01
J 2
(-766 2238);
DISPLAY 0.574468 (-766 2238);
PAINT GREEN (-766 2238);
DISPLAY INVISIBLE (-766 2238);
FORCEPROP 1 LAST LOCATION C852
J 0
(-400 2225);
DISPLAY 1.021277 (-400 2225);
DISPLAY INVISIBLE (-400 2225);
FORCEPROP 1 LAST PATH I61
J 2
(-650 2150);
DISPLAY 0.723404 (-650 2150);
DISPLAY INVISIBLE (-650 2150);
FORCEADD Q_CAP_DIFFBUS..2
R 2
(-650 2100);
FORCEPROP 1 LAST LOCATION C853
J 2
(-416 2117);
DISPLAY 0.723404 (-416 2117);
PAINT GREEN (-416 2117);
FORCEPROP 2 LAST $SEC 1
J 2
(-475 2175);
DISPLAY 0.680851 (-475 2175);
PAINT MONO (-475 2175);
DISPLAY INVISIBLE (-475 2175);
FORCEPROP 2 LAST CDS_SEC 1
J 2
(-475 2175);
DISPLAY 0.680851 (-475 2175);
DISPLAY INVISIBLE (-475 2175);
FORCEPROP 2 LASTPIN (-575 2100) $PN 1
J 0
(-565 2110);
DISPLAY 0.808511 (-565 2110);
FORCEPROP 2 LASTPIN (-725 2100) $PN 2
J 2
(-735 2110);
DISPLAY 0.808511 (-735 2110);
FORCEPROP 2 LAST VALUE DIFF BUS_0.22UF
J 2
(-800 2100);
DISPLAY 0.553191 (-800 2100);
FORCEPROP 2 LAST TOLERANCE 20%
J 2
(-725 2150);
DISPLAY 0.553191 (-725 2150);
DISPLAY INVISIBLE (-725 2150);
FORCEPROP 2 LAST PACK_TYPE C0201
J 2
(-825 2150);
DISPLAY 0.553191 (-825 2150);
DISPLAY INVISIBLE (-825 2150);
FORCEPROP 1 LAST MATERIAL X6S
J 2
(-641 2179);
DISPLAY 0.574468 (-641 2179);
PAINT GREEN (-641 2179);
DISPLAY INVISIBLE (-641 2179);
FORCEPROP 2 LAST VOLTAGE 6.3V
J 2
(-1000 2150);
DISPLAY 0.553191 (-1000 2150);
DISPLAY INVISIBLE (-1000 2150);
FORCEPROP 1 LAST PIN_NAMES_ROTATE TRUE
J 2
(-650 2100);
DISPLAY 0.489362 (-650 2100);
PAINT GREEN (-650 2100);
DISPLAY INVISIBLE (-650 2100);
FORCEPROP 2 LAST CDS_LIB pure_quanta
J 2
(-650 2100);
DISPLAY INVISIBLE (-650 2100);
FORCEPROP 1 LAST CDS_LMAN_SYM_OUTLINE -25,50,25,-50
J 2
(-650 2100);
DISPLAY 0.468085 (-650 2100);
PAINT GREEN (-650 2100);
DISPLAY INVISIBLE (-650 2100);
FORCEPROP 1 LAST PART_NUMBER SP_CH4221MEE01
J 2
(-766 2188);
DISPLAY 0.574468 (-766 2188);
PAINT GREEN (-766 2188);
DISPLAY INVISIBLE (-766 2188);
FORCEPROP 1 LAST LOCATION C853
J 0
(-400 2175);
DISPLAY 1.021277 (-400 2175);
DISPLAY INVISIBLE (-400 2175);
FORCEPROP 1 LAST PATH I62
J 2
(-650 2100);
DISPLAY 0.723404 (-650 2100);
DISPLAY INVISIBLE (-650 2100);
FORCEADD Q_CAP_DIFFBUS..2
R 2
(-650 2300);
FORCEPROP 1 LAST LOCATION C851
J 2
(-416 2317);
DISPLAY 0.723404 (-416 2317);
PAINT GREEN (-416 2317);
FORCEPROP 2 LAST $SEC 1
J 2
(-475 2375);
DISPLAY 0.680851 (-475 2375);
PAINT MONO (-475 2375);
DISPLAY INVISIBLE (-475 2375);
FORCEPROP 2 LAST CDS_SEC 1
J 2
(-475 2375);
DISPLAY 0.680851 (-475 2375);
DISPLAY INVISIBLE (-475 2375);
FORCEPROP 2 LASTPIN (-575 2300) $PN 1
J 0
(-565 2310);
DISPLAY 0.808511 (-565 2310);
FORCEPROP 2 LASTPIN (-725 2300) $PN 2
J 2
(-735 2310);
DISPLAY 0.808511 (-735 2310);
FORCEPROP 2 LAST VALUE DIFF BUS_0.22UF
J 2
(-800 2300);
DISPLAY 0.553191 (-800 2300);
FORCEPROP 2 LAST TOLERANCE 20%
J 2
(-725 2350);
DISPLAY 0.553191 (-725 2350);
DISPLAY INVISIBLE (-725 2350);
FORCEPROP 2 LAST PACK_TYPE C0201
J 2
(-825 2350);
DISPLAY 0.553191 (-825 2350);
DISPLAY INVISIBLE (-825 2350);
FORCEPROP 1 LAST MATERIAL X6S
J 2
(-641 2379);
DISPLAY 0.574468 (-641 2379);
PAINT GREEN (-641 2379);
DISPLAY INVISIBLE (-641 2379);
FORCEPROP 2 LAST VOLTAGE 6.3V
J 2
(-1000 2350);
DISPLAY 0.553191 (-1000 2350);
DISPLAY INVISIBLE (-1000 2350);
FORCEPROP 1 LAST PIN_NAMES_ROTATE TRUE
J 2
(-650 2300);
DISPLAY 0.489362 (-650 2300);
PAINT GREEN (-650 2300);
DISPLAY INVISIBLE (-650 2300);
FORCEPROP 2 LAST CDS_LIB pure_quanta
J 2
(-650 2300);
DISPLAY INVISIBLE (-650 2300);
FORCEPROP 1 LAST CDS_LMAN_SYM_OUTLINE -25,50,25,-50
J 2
(-650 2300);
DISPLAY 0.468085 (-650 2300);
PAINT GREEN (-650 2300);
DISPLAY INVISIBLE (-650 2300);
FORCEPROP 1 LAST PART_NUMBER SP_CH4221MEE01
J 2
(-766 2388);
DISPLAY 0.574468 (-766 2388);
PAINT GREEN (-766 2388);
DISPLAY INVISIBLE (-766 2388);
FORCEPROP 1 LAST LOCATION C851
J 0
(-400 2375);
DISPLAY 1.021277 (-400 2375);
DISPLAY INVISIBLE (-400 2375);
FORCEPROP 1 LAST PATH I63
J 2
(-650 2300);
DISPLAY 0.723404 (-650 2300);
DISPLAY INVISIBLE (-650 2300);
FORCEADD Q_CAP_DIFFBUS..2
R 2
(-650 2350);
FORCEPROP 1 LAST LOCATION C850
J 2
(-416 2367);
DISPLAY 0.723404 (-416 2367);
PAINT GREEN (-416 2367);
FORCEPROP 2 LAST $SEC 1
J 2
(-475 2425);
DISPLAY 0.680851 (-475 2425);
PAINT MONO (-475 2425);
DISPLAY INVISIBLE (-475 2425);
FORCEPROP 2 LAST CDS_SEC 1
J 2
(-475 2425);
DISPLAY 0.680851 (-475 2425);
DISPLAY INVISIBLE (-475 2425);
FORCEPROP 2 LASTPIN (-575 2350) $PN 1
J 0
(-565 2360);
DISPLAY 0.808511 (-565 2360);
FORCEPROP 2 LASTPIN (-725 2350) $PN 2
J 2
(-735 2360);
DISPLAY 0.808511 (-735 2360);
FORCEPROP 2 LAST VALUE DIFF BUS_0.22UF
J 2
(-800 2350);
DISPLAY 0.553191 (-800 2350);
FORCEPROP 2 LAST TOLERANCE 20%
J 2
(-725 2400);
DISPLAY 0.553191 (-725 2400);
DISPLAY INVISIBLE (-725 2400);
FORCEPROP 2 LAST PACK_TYPE C0201
J 2
(-825 2400);
DISPLAY 0.553191 (-825 2400);
DISPLAY INVISIBLE (-825 2400);
FORCEPROP 1 LAST MATERIAL X6S
J 2
(-641 2429);
DISPLAY 0.574468 (-641 2429);
PAINT GREEN (-641 2429);
DISPLAY INVISIBLE (-641 2429);
FORCEPROP 2 LAST VOLTAGE 6.3V
J 2
(-1000 2400);
DISPLAY 0.553191 (-1000 2400);
DISPLAY INVISIBLE (-1000 2400);
FORCEPROP 1 LAST PIN_NAMES_ROTATE TRUE
J 2
(-650 2350);
DISPLAY 0.489362 (-650 2350);
PAINT GREEN (-650 2350);
DISPLAY INVISIBLE (-650 2350);
FORCEPROP 1 LAST CDS_LMAN_SYM_OUTLINE -25,50,25,-50
J 2
(-650 2350);
DISPLAY 0.468085 (-650 2350);
PAINT GREEN (-650 2350);
DISPLAY INVISIBLE (-650 2350);
FORCEPROP 2 LAST CDS_LIB pure_quanta
J 2
(-650 2350);
DISPLAY INVISIBLE (-650 2350);
FORCEPROP 1 LAST PART_NUMBER SP_CH4221MEE01
J 2
(-766 2438);
DISPLAY 0.574468 (-766 2438);
PAINT GREEN (-766 2438);
DISPLAY INVISIBLE (-766 2438);
FORCEPROP 1 LAST LOCATION C850
J 0
(-400 2425);
DISPLAY 1.021277 (-400 2425);
DISPLAY INVISIBLE (-400 2425);
FORCEPROP 1 LAST PATH I64
J 2
(-650 2350);
DISPLAY 0.723404 (-650 2350);
DISPLAY INVISIBLE (-650 2350);
FORCEADD Q_CAP_DIFFBUS..2
R 2
(-650 2500);
FORCEPROP 1 LAST LOCATION C849
J 2
(-416 2517);
DISPLAY 0.723404 (-416 2517);
PAINT GREEN (-416 2517);
FORCEPROP 2 LAST $SEC 1
J 2
(-475 2575);
DISPLAY 0.680851 (-475 2575);
PAINT MONO (-475 2575);
DISPLAY INVISIBLE (-475 2575);
FORCEPROP 2 LAST CDS_SEC 1
J 2
(-475 2575);
DISPLAY 0.680851 (-475 2575);
DISPLAY INVISIBLE (-475 2575);
FORCEPROP 2 LASTPIN (-575 2500) $PN 1
J 0
(-565 2510);
DISPLAY 0.808511 (-565 2510);
FORCEPROP 2 LASTPIN (-725 2500) $PN 2
J 2
(-735 2510);
DISPLAY 0.808511 (-735 2510);
FORCEPROP 2 LAST VALUE DIFF BUS_0.22UF
J 2
(-800 2500);
DISPLAY 0.553191 (-800 2500);
FORCEPROP 2 LAST TOLERANCE 20%
J 2
(-725 2550);
DISPLAY 0.553191 (-725 2550);
DISPLAY INVISIBLE (-725 2550);
FORCEPROP 2 LAST PACK_TYPE C0201
J 2
(-825 2550);
DISPLAY 0.553191 (-825 2550);
DISPLAY INVISIBLE (-825 2550);
FORCEPROP 1 LAST MATERIAL X6S
J 2
(-641 2579);
DISPLAY 0.574468 (-641 2579);
PAINT GREEN (-641 2579);
DISPLAY INVISIBLE (-641 2579);
FORCEPROP 2 LAST VOLTAGE 6.3V
J 2
(-1000 2550);
DISPLAY 0.553191 (-1000 2550);
DISPLAY INVISIBLE (-1000 2550);
FORCEPROP 1 LAST PIN_NAMES_ROTATE TRUE
J 2
(-650 2500);
DISPLAY 0.489362 (-650 2500);
PAINT GREEN (-650 2500);
DISPLAY INVISIBLE (-650 2500);
FORCEPROP 2 LAST CDS_LIB pure_quanta
J 2
(-650 2500);
DISPLAY INVISIBLE (-650 2500);
FORCEPROP 1 LAST CDS_LMAN_SYM_OUTLINE -25,50,25,-50
J 2
(-650 2500);
DISPLAY 0.468085 (-650 2500);
PAINT GREEN (-650 2500);
DISPLAY INVISIBLE (-650 2500);
FORCEPROP 1 LAST PART_NUMBER SP_CH4221MEE01
J 2
(-766 2588);
DISPLAY 0.574468 (-766 2588);
PAINT GREEN (-766 2588);
DISPLAY INVISIBLE (-766 2588);
FORCEPROP 1 LAST LOCATION C849
J 0
(-400 2575);
DISPLAY 1.021277 (-400 2575);
DISPLAY INVISIBLE (-400 2575);
FORCEPROP 1 LAST PATH I65
J 2
(-650 2500);
DISPLAY 0.723404 (-650 2500);
DISPLAY INVISIBLE (-650 2500);
FORCEADD Q_CAP_DIFFBUS..2
R 2
(-650 2550);
FORCEPROP 1 LAST LOCATION C848
J 2
(-416 2567);
DISPLAY 0.723404 (-416 2567);
PAINT GREEN (-416 2567);
FORCEPROP 2 LAST $SEC 1
J 2
(-475 2625);
DISPLAY 0.680851 (-475 2625);
PAINT MONO (-475 2625);
DISPLAY INVISIBLE (-475 2625);
FORCEPROP 2 LAST CDS_SEC 1
J 2
(-475 2625);
DISPLAY 0.680851 (-475 2625);
DISPLAY INVISIBLE (-475 2625);
FORCEPROP 2 LASTPIN (-575 2550) $PN 1
J 0
(-565 2560);
DISPLAY 0.808511 (-565 2560);
FORCEPROP 2 LASTPIN (-725 2550) $PN 2
J 2
(-735 2560);
DISPLAY 0.808511 (-735 2560);
FORCEPROP 2 LAST VALUE DIFF BUS_0.22UF
J 2
(-800 2550);
DISPLAY 0.553191 (-800 2550);
FORCEPROP 2 LAST TOLERANCE 20%
J 2
(-725 2600);
DISPLAY 0.553191 (-725 2600);
DISPLAY INVISIBLE (-725 2600);
FORCEPROP 2 LAST PACK_TYPE C0201
J 2
(-825 2600);
DISPLAY 0.553191 (-825 2600);
DISPLAY INVISIBLE (-825 2600);
FORCEPROP 1 LAST MATERIAL X6S
J 2
(-641 2629);
DISPLAY 0.574468 (-641 2629);
PAINT GREEN (-641 2629);
DISPLAY INVISIBLE (-641 2629);
FORCEPROP 2 LAST VOLTAGE 6.3V
J 2
(-1000 2600);
DISPLAY 0.553191 (-1000 2600);
DISPLAY INVISIBLE (-1000 2600);
FORCEPROP 1 LAST PIN_NAMES_ROTATE TRUE
J 2
(-650 2550);
DISPLAY 0.489362 (-650 2550);
PAINT GREEN (-650 2550);
DISPLAY INVISIBLE (-650 2550);
FORCEPROP 2 LAST CDS_LIB pure_quanta
J 2
(-650 2550);
DISPLAY INVISIBLE (-650 2550);
FORCEPROP 1 LAST CDS_LMAN_SYM_OUTLINE -25,50,25,-50
J 2
(-650 2550);
DISPLAY 0.468085 (-650 2550);
PAINT GREEN (-650 2550);
DISPLAY INVISIBLE (-650 2550);
FORCEPROP 1 LAST PART_NUMBER SP_CH4221MEE01
J 2
(-766 2638);
DISPLAY 0.574468 (-766 2638);
PAINT GREEN (-766 2638);
DISPLAY INVISIBLE (-766 2638);
FORCEPROP 1 LAST LOCATION C848
J 0
(-400 2625);
DISPLAY 1.021277 (-400 2625);
DISPLAY INVISIBLE (-400 2625);
FORCEPROP 1 LAST PATH I66
J 2
(-650 2550);
DISPLAY 0.723404 (-650 2550);
DISPLAY INVISIBLE (-650 2550);
FORCEADD Q_CAP_DIFFBUS..2
R 2
(-650 2700);
FORCEPROP 1 LAST LOCATION C847
J 2
(-416 2717);
DISPLAY 0.723404 (-416 2717);
PAINT GREEN (-416 2717);
FORCEPROP 2 LAST $SEC 1
J 2
(-475 2775);
DISPLAY 0.680851 (-475 2775);
PAINT MONO (-475 2775);
DISPLAY INVISIBLE (-475 2775);
FORCEPROP 2 LAST CDS_SEC 1
J 2
(-475 2775);
DISPLAY 0.680851 (-475 2775);
DISPLAY INVISIBLE (-475 2775);
FORCEPROP 2 LASTPIN (-575 2700) $PN 1
J 0
(-565 2710);
DISPLAY 0.808511 (-565 2710);
FORCEPROP 2 LASTPIN (-725 2700) $PN 2
J 2
(-735 2710);
DISPLAY 0.808511 (-735 2710);
FORCEPROP 2 LAST VALUE DIFF BUS_0.22UF
J 2
(-800 2700);
DISPLAY 0.553191 (-800 2700);
FORCEPROP 2 LAST TOLERANCE 20%
J 2
(-725 2750);
DISPLAY 0.553191 (-725 2750);
DISPLAY INVISIBLE (-725 2750);
FORCEPROP 2 LAST PACK_TYPE C0201
J 2
(-825 2750);
DISPLAY 0.553191 (-825 2750);
DISPLAY INVISIBLE (-825 2750);
FORCEPROP 1 LAST MATERIAL X6S
J 2
(-641 2779);
DISPLAY 0.574468 (-641 2779);
PAINT GREEN (-641 2779);
DISPLAY INVISIBLE (-641 2779);
FORCEPROP 2 LAST VOLTAGE 6.3V
J 2
(-1000 2750);
DISPLAY 0.553191 (-1000 2750);
DISPLAY INVISIBLE (-1000 2750);
FORCEPROP 1 LAST PIN_NAMES_ROTATE TRUE
J 2
(-650 2700);
DISPLAY 0.489362 (-650 2700);
PAINT GREEN (-650 2700);
DISPLAY INVISIBLE (-650 2700);
FORCEPROP 1 LAST CDS_LMAN_SYM_OUTLINE -25,50,25,-50
J 2
(-650 2700);
DISPLAY 0.468085 (-650 2700);
PAINT GREEN (-650 2700);
DISPLAY INVISIBLE (-650 2700);
FORCEPROP 2 LAST CDS_LIB pure_quanta
J 2
(-650 2700);
DISPLAY INVISIBLE (-650 2700);
FORCEPROP 1 LAST PART_NUMBER SP_CH4221MEE01
J 2
(-766 2788);
DISPLAY 0.574468 (-766 2788);
PAINT GREEN (-766 2788);
DISPLAY INVISIBLE (-766 2788);
FORCEPROP 1 LAST LOCATION C847
J 0
(-400 2775);
DISPLAY 1.021277 (-400 2775);
DISPLAY INVISIBLE (-400 2775);
FORCEPROP 1 LAST PATH I67
J 2
(-650 2700);
DISPLAY 0.723404 (-650 2700);
DISPLAY INVISIBLE (-650 2700);
FORCEADD Q_CAP_DIFFBUS..2
R 2
(-650 2750);
FORCEPROP 1 LAST LOCATION C846
J 2
(-416 2767);
DISPLAY 0.723404 (-416 2767);
PAINT GREEN (-416 2767);
FORCEPROP 2 LAST $SEC 1
J 2
(-475 2825);
DISPLAY 0.680851 (-475 2825);
PAINT MONO (-475 2825);
DISPLAY INVISIBLE (-475 2825);
FORCEPROP 2 LAST CDS_SEC 1
J 2
(-475 2825);
DISPLAY 0.680851 (-475 2825);
DISPLAY INVISIBLE (-475 2825);
FORCEPROP 2 LASTPIN (-575 2750) $PN 1
J 0
(-565 2760);
DISPLAY 0.808511 (-565 2760);
FORCEPROP 2 LASTPIN (-725 2750) $PN 2
J 2
(-735 2760);
DISPLAY 0.808511 (-735 2760);
FORCEPROP 2 LAST VALUE DIFF BUS_0.22UF
J 2
(-800 2750);
DISPLAY 0.553191 (-800 2750);
FORCEPROP 2 LAST TOLERANCE 20%
J 2
(-725 2800);
DISPLAY 0.553191 (-725 2800);
DISPLAY INVISIBLE (-725 2800);
FORCEPROP 2 LAST PACK_TYPE C0201
J 2
(-825 2800);
DISPLAY 0.553191 (-825 2800);
DISPLAY INVISIBLE (-825 2800);
FORCEPROP 1 LAST MATERIAL X6S
J 2
(-641 2829);
DISPLAY 0.574468 (-641 2829);
PAINT GREEN (-641 2829);
DISPLAY INVISIBLE (-641 2829);
FORCEPROP 2 LAST VOLTAGE 6.3V
J 2
(-1000 2800);
DISPLAY 0.553191 (-1000 2800);
DISPLAY INVISIBLE (-1000 2800);
FORCEPROP 1 LAST PIN_NAMES_ROTATE TRUE
J 2
(-650 2750);
DISPLAY 0.489362 (-650 2750);
PAINT GREEN (-650 2750);
DISPLAY INVISIBLE (-650 2750);
FORCEPROP 1 LAST CDS_LMAN_SYM_OUTLINE -25,50,25,-50
J 2
(-650 2750);
DISPLAY 0.468085 (-650 2750);
PAINT GREEN (-650 2750);
DISPLAY INVISIBLE (-650 2750);
FORCEPROP 2 LAST CDS_LIB pure_quanta
J 2
(-650 2750);
DISPLAY INVISIBLE (-650 2750);
FORCEPROP 1 LAST PART_NUMBER SP_CH4221MEE01
J 2
(-766 2838);
DISPLAY 0.574468 (-766 2838);
PAINT GREEN (-766 2838);
DISPLAY INVISIBLE (-766 2838);
FORCEPROP 1 LAST LOCATION C846
J 0
(-400 2825);
DISPLAY 1.021277 (-400 2825);
DISPLAY INVISIBLE (-400 2825);
FORCEPROP 1 LAST PATH I68
J 2
(-650 2750);
DISPLAY 0.723404 (-650 2750);
DISPLAY INVISIBLE (-650 2750);
FORCEADD Q_CAP_DIFFBUS..2
R 2
(-650 2900);
FORCEPROP 1 LAST LOCATION C845
J 2
(-416 2917);
DISPLAY 0.723404 (-416 2917);
PAINT GREEN (-416 2917);
FORCEPROP 2 LAST $SEC 1
J 2
(-475 2975);
DISPLAY 0.680851 (-475 2975);
PAINT MONO (-475 2975);
DISPLAY INVISIBLE (-475 2975);
FORCEPROP 2 LAST CDS_SEC 1
J 2
(-475 2975);
DISPLAY 0.680851 (-475 2975);
DISPLAY INVISIBLE (-475 2975);
FORCEPROP 2 LASTPIN (-575 2900) $PN 1
J 0
(-565 2910);
DISPLAY 0.808511 (-565 2910);
FORCEPROP 2 LASTPIN (-725 2900) $PN 2
J 2
(-735 2910);
DISPLAY 0.808511 (-735 2910);
FORCEPROP 2 LAST VALUE DIFF BUS_0.22UF
J 2
(-800 2900);
DISPLAY 0.553191 (-800 2900);
FORCEPROP 2 LAST TOLERANCE 20%
J 2
(-725 2950);
DISPLAY 0.553191 (-725 2950);
DISPLAY INVISIBLE (-725 2950);
FORCEPROP 2 LAST PACK_TYPE C0201
J 2
(-825 2950);
DISPLAY 0.553191 (-825 2950);
DISPLAY INVISIBLE (-825 2950);
FORCEPROP 1 LAST MATERIAL X6S
J 2
(-641 2979);
DISPLAY 0.574468 (-641 2979);
PAINT GREEN (-641 2979);
DISPLAY INVISIBLE (-641 2979);
FORCEPROP 2 LAST VOLTAGE 6.3V
J 2
(-1000 2950);
DISPLAY 0.553191 (-1000 2950);
DISPLAY INVISIBLE (-1000 2950);
FORCEPROP 1 LAST PIN_NAMES_ROTATE TRUE
J 2
(-650 2900);
DISPLAY 0.489362 (-650 2900);
PAINT GREEN (-650 2900);
DISPLAY INVISIBLE (-650 2900);
FORCEPROP 2 LAST CDS_LIB pure_quanta
J 2
(-650 2900);
DISPLAY INVISIBLE (-650 2900);
FORCEPROP 1 LAST CDS_LMAN_SYM_OUTLINE -25,50,25,-50
J 2
(-650 2900);
DISPLAY 0.468085 (-650 2900);
PAINT GREEN (-650 2900);
DISPLAY INVISIBLE (-650 2900);
FORCEPROP 1 LAST PART_NUMBER SP_CH4221MEE01
J 2
(-766 2988);
DISPLAY 0.574468 (-766 2988);
PAINT GREEN (-766 2988);
DISPLAY INVISIBLE (-766 2988);
FORCEPROP 1 LAST LOCATION C845
J 0
(-400 2975);
DISPLAY 1.021277 (-400 2975);
DISPLAY INVISIBLE (-400 2975);
FORCEPROP 1 LAST PATH I69
J 2
(-650 2900);
DISPLAY 0.723404 (-650 2900);
DISPLAY INVISIBLE (-650 2900);
FORCEADD TAP..1
R 2
(-1625 525);
FORCEPROP 3 LASTPIN (-1575 525) SIG_NAME P5E_CPU0_P2_TX_DP<2>
J 0
(-1565 535);
DISPLAY 0.659574 (-1565 535);
PAINT MONO (-1565 535);
DISPLAY INVISIBLE (-1565 535);
FORCEPROP 1 LASTPIN (-1575 525) BN 2
J 2
(-1563 533);
DISPLAY 0.680851 (-1563 533);
PAINT GREEN (-1563 533);
FORCEPROP 2 LAST CDS_LIB standard
J 0
(-1625 525);
DISPLAY INVISIBLE (-1625 525);
FORCEPROP 1 LAST BODY_TYPE PLUMBING
J 2
(-1625 575);
DISPLAY 0.872340 (-1625 575);
PAINT GREEN (-1625 575);
DISPLAY INVISIBLE (-1625 575);
FORCEPROP 1 LAST HDL_TAP TRUE
J 2
(-1950 400);
DISPLAY 0.872340 (-1950 400);
DISPLAY INVISIBLE (-1950 400);
FORCEPROP 1 LAST PATH I7
J 2
(-1623 525);
DISPLAY 0.872340 (-1623 525);
PAINT GREEN (-1623 525);
DISPLAY INVISIBLE (-1623 525);
FORCEADD Q_CAP_DIFFBUS..2
R 2
(-650 2950);
FORCEPROP 1 LAST LOCATION C844
J 2
(-416 2967);
DISPLAY 0.723404 (-416 2967);
PAINT GREEN (-416 2967);
FORCEPROP 2 LAST $SEC 1
J 2
(-475 3025);
DISPLAY 0.680851 (-475 3025);
PAINT MONO (-475 3025);
DISPLAY INVISIBLE (-475 3025);
FORCEPROP 2 LAST CDS_SEC 1
J 2
(-475 3025);
DISPLAY 0.680851 (-475 3025);
DISPLAY INVISIBLE (-475 3025);
FORCEPROP 2 LASTPIN (-575 2950) $PN 1
J 0
(-565 2960);
DISPLAY 0.808511 (-565 2960);
FORCEPROP 2 LASTPIN (-725 2950) $PN 2
J 2
(-735 2960);
DISPLAY 0.808511 (-735 2960);
FORCEPROP 2 LAST VALUE DIFF BUS_0.22UF
J 2
(-800 2950);
DISPLAY 0.553191 (-800 2950);
FORCEPROP 2 LAST TOLERANCE 20%
J 2
(-725 3000);
DISPLAY 0.553191 (-725 3000);
DISPLAY INVISIBLE (-725 3000);
FORCEPROP 2 LAST PACK_TYPE C0201
J 2
(-825 3000);
DISPLAY 0.553191 (-825 3000);
DISPLAY INVISIBLE (-825 3000);
FORCEPROP 1 LAST MATERIAL X6S
J 2
(-641 3029);
DISPLAY 0.574468 (-641 3029);
PAINT GREEN (-641 3029);
DISPLAY INVISIBLE (-641 3029);
FORCEPROP 2 LAST VOLTAGE 6.3V
J 2
(-1000 3000);
DISPLAY 0.553191 (-1000 3000);
DISPLAY INVISIBLE (-1000 3000);
FORCEPROP 1 LAST PIN_NAMES_ROTATE TRUE
J 2
(-650 2950);
DISPLAY 0.489362 (-650 2950);
PAINT GREEN (-650 2950);
DISPLAY INVISIBLE (-650 2950);
FORCEPROP 2 LAST CDS_LIB pure_quanta
J 2
(-650 2950);
DISPLAY INVISIBLE (-650 2950);
FORCEPROP 1 LAST CDS_LMAN_SYM_OUTLINE -25,50,25,-50
J 2
(-650 2950);
DISPLAY 0.468085 (-650 2950);
PAINT GREEN (-650 2950);
DISPLAY INVISIBLE (-650 2950);
FORCEPROP 1 LAST PART_NUMBER SP_CH4221MEE01
J 2
(-766 3038);
DISPLAY 0.574468 (-766 3038);
PAINT GREEN (-766 3038);
DISPLAY INVISIBLE (-766 3038);
FORCEPROP 1 LAST LOCATION C844
J 0
(-400 3025);
DISPLAY 1.021277 (-400 3025);
DISPLAY INVISIBLE (-400 3025);
FORCEPROP 1 LAST PATH I70
J 2
(-650 2950);
DISPLAY 0.723404 (-650 2950);
DISPLAY INVISIBLE (-650 2950);
FORCEADD TAP..1
(-100 2150);
FORCEPROP 3 LASTPIN (-150 2150) SIG_NAME P5E_CPU0_P2_TX_C_DN<8>
J 0
(-140 2160);
DISPLAY 0.659574 (-140 2160);
PAINT MONO (-140 2160);
DISPLAY INVISIBLE (-140 2160);
FORCEPROP 1 LASTPIN (-150 2150) BN 8
J 0
(-162 2158);
DISPLAY 0.680851 (-162 2158);
PAINT GREEN (-162 2158);
FORCEPROP 2 LAST CDS_LIB standard
J 0
(-100 2150);
DISPLAY INVISIBLE (-100 2150);
FORCEPROP 1 LAST BODY_TYPE PLUMBING
J 0
(-100 2200);
DISPLAY 0.872340 (-100 2200);
PAINT GREEN (-100 2200);
DISPLAY INVISIBLE (-100 2200);
FORCEPROP 1 LAST HDL_TAP TRUE
J 0
(225 2025);
DISPLAY 0.872340 (225 2025);
DISPLAY INVISIBLE (225 2025);
FORCEPROP 1 LAST PATH I71
J 0
(-102 2150);
DISPLAY 0.872340 (-102 2150);
PAINT GREEN (-102 2150);
DISPLAY INVISIBLE (-102 2150);
FORCEADD TAP..1
(-100 2350);
FORCEPROP 3 LASTPIN (-150 2350) SIG_NAME P5E_CPU0_P2_TX_C_DN<9>
J 0
(-140 2360);
DISPLAY 0.659574 (-140 2360);
PAINT MONO (-140 2360);
DISPLAY INVISIBLE (-140 2360);
FORCEPROP 1 LASTPIN (-150 2350) BN 9
J 0
(-162 2358);
DISPLAY 0.680851 (-162 2358);
PAINT GREEN (-162 2358);
FORCEPROP 2 LAST CDS_LIB standard
J 0
(-100 2350);
DISPLAY INVISIBLE (-100 2350);
FORCEPROP 1 LAST BODY_TYPE PLUMBING
J 0
(-100 2400);
DISPLAY 0.872340 (-100 2400);
PAINT GREEN (-100 2400);
DISPLAY INVISIBLE (-100 2400);
FORCEPROP 1 LAST HDL_TAP TRUE
J 0
(225 2225);
DISPLAY 0.872340 (225 2225);
DISPLAY INVISIBLE (225 2225);
FORCEPROP 1 LAST PATH I72
J 0
(-102 2350);
DISPLAY 0.872340 (-102 2350);
PAINT GREEN (-102 2350);
DISPLAY INVISIBLE (-102 2350);
FORCEADD TAP..1
(-100 2550);
FORCEPROP 3 LASTPIN (-150 2550) SIG_NAME P5E_CPU0_P2_TX_C_DN<10>
J 0
(-140 2560);
DISPLAY 0.659574 (-140 2560);
PAINT MONO (-140 2560);
DISPLAY INVISIBLE (-140 2560);
FORCEPROP 1 LASTPIN (-150 2550) BN 10
J 0
(-162 2558);
DISPLAY 0.680851 (-162 2558);
PAINT GREEN (-162 2558);
FORCEPROP 2 LAST CDS_LIB standard
J 0
(-100 2550);
DISPLAY INVISIBLE (-100 2550);
FORCEPROP 1 LAST BODY_TYPE PLUMBING
J 0
(-100 2600);
DISPLAY 0.872340 (-100 2600);
PAINT GREEN (-100 2600);
DISPLAY INVISIBLE (-100 2600);
FORCEPROP 1 LAST HDL_TAP TRUE
J 0
(225 2425);
DISPLAY 0.872340 (225 2425);
DISPLAY INVISIBLE (225 2425);
FORCEPROP 1 LAST PATH I73
J 0
(-102 2550);
DISPLAY 0.872340 (-102 2550);
PAINT GREEN (-102 2550);
DISPLAY INVISIBLE (-102 2550);
FORCEADD TAP..1
(-100 2750);
FORCEPROP 3 LASTPIN (-150 2750) SIG_NAME P5E_CPU0_P2_TX_C_DN<11>
J 0
(-140 2760);
DISPLAY 0.659574 (-140 2760);
PAINT MONO (-140 2760);
DISPLAY INVISIBLE (-140 2760);
FORCEPROP 1 LASTPIN (-150 2750) BN 11
J 0
(-162 2758);
DISPLAY 0.680851 (-162 2758);
PAINT GREEN (-162 2758);
FORCEPROP 2 LAST CDS_LIB standard
J 0
(-100 2750);
DISPLAY INVISIBLE (-100 2750);
FORCEPROP 1 LAST BODY_TYPE PLUMBING
J 0
(-100 2800);
DISPLAY 0.872340 (-100 2800);
PAINT GREEN (-100 2800);
DISPLAY INVISIBLE (-100 2800);
FORCEPROP 1 LAST HDL_TAP TRUE
J 0
(225 2625);
DISPLAY 0.872340 (225 2625);
DISPLAY INVISIBLE (225 2625);
FORCEPROP 1 LAST PATH I74
J 0
(-102 2750);
DISPLAY 0.872340 (-102 2750);
PAINT GREEN (-102 2750);
DISPLAY INVISIBLE (-102 2750);
FORCEADD TAP..1
(-100 2950);
FORCEPROP 3 LASTPIN (-150 2950) SIG_NAME P5E_CPU0_P2_TX_C_DN<12>
J 0
(-140 2960);
DISPLAY 0.659574 (-140 2960);
PAINT MONO (-140 2960);
DISPLAY INVISIBLE (-140 2960);
FORCEPROP 1 LASTPIN (-150 2950) BN 12
J 0
(-162 2958);
DISPLAY 0.680851 (-162 2958);
PAINT GREEN (-162 2958);
FORCEPROP 2 LAST CDS_LIB standard
J 0
(-100 2950);
DISPLAY INVISIBLE (-100 2950);
FORCEPROP 1 LAST BODY_TYPE PLUMBING
J 0
(-100 3000);
DISPLAY 0.872340 (-100 3000);
PAINT GREEN (-100 3000);
DISPLAY INVISIBLE (-100 3000);
FORCEPROP 1 LAST HDL_TAP TRUE
J 0
(225 2825);
DISPLAY 0.872340 (225 2825);
DISPLAY INVISIBLE (225 2825);
FORCEPROP 1 LAST PATH I75
J 0
(-102 2950);
DISPLAY 0.872340 (-102 2950);
PAINT GREEN (-102 2950);
DISPLAY INVISIBLE (-102 2950);
FORCEADD Q_CAP_DIFFBUS..2
R 2
(-650 3150);
FORCEPROP 1 LAST LOCATION C842
J 2
(-416 3167);
DISPLAY 0.723404 (-416 3167);
PAINT GREEN (-416 3167);
FORCEPROP 2 LAST $SEC 1
J 2
(-475 3225);
DISPLAY 0.680851 (-475 3225);
PAINT MONO (-475 3225);
DISPLAY INVISIBLE (-475 3225);
FORCEPROP 2 LAST CDS_SEC 1
J 2
(-475 3225);
DISPLAY 0.680851 (-475 3225);
DISPLAY INVISIBLE (-475 3225);
FORCEPROP 2 LASTPIN (-575 3150) $PN 1
J 0
(-565 3160);
DISPLAY 0.808511 (-565 3160);
FORCEPROP 2 LASTPIN (-725 3150) $PN 2
J 2
(-735 3160);
DISPLAY 0.808511 (-735 3160);
FORCEPROP 2 LAST VALUE DIFF BUS_0.22UF
J 2
(-800 3150);
DISPLAY 0.553191 (-800 3150);
FORCEPROP 2 LAST TOLERANCE 20%
J 2
(-725 3200);
DISPLAY 0.553191 (-725 3200);
DISPLAY INVISIBLE (-725 3200);
FORCEPROP 2 LAST PACK_TYPE C0201
J 2
(-825 3200);
DISPLAY 0.553191 (-825 3200);
DISPLAY INVISIBLE (-825 3200);
FORCEPROP 1 LAST MATERIAL X6S
J 2
(-641 3229);
DISPLAY 0.574468 (-641 3229);
PAINT GREEN (-641 3229);
DISPLAY INVISIBLE (-641 3229);
FORCEPROP 2 LAST VOLTAGE 6.3V
J 2
(-1000 3200);
DISPLAY 0.553191 (-1000 3200);
DISPLAY INVISIBLE (-1000 3200);
FORCEPROP 1 LAST PIN_NAMES_ROTATE TRUE
J 2
(-650 3150);
DISPLAY 0.489362 (-650 3150);
PAINT GREEN (-650 3150);
DISPLAY INVISIBLE (-650 3150);
FORCEPROP 2 LAST CDS_LIB pure_quanta
J 2
(-650 3150);
DISPLAY INVISIBLE (-650 3150);
FORCEPROP 1 LAST CDS_LMAN_SYM_OUTLINE -25,50,25,-50
J 2
(-650 3150);
DISPLAY 0.468085 (-650 3150);
PAINT GREEN (-650 3150);
DISPLAY INVISIBLE (-650 3150);
FORCEPROP 1 LAST PART_NUMBER SP_CH4221MEE01
J 2
(-766 3238);
DISPLAY 0.574468 (-766 3238);
PAINT GREEN (-766 3238);
DISPLAY INVISIBLE (-766 3238);
FORCEPROP 1 LAST LOCATION C842
J 0
(-400 3225);
DISPLAY 1.021277 (-400 3225);
DISPLAY INVISIBLE (-400 3225);
FORCEPROP 1 LAST PATH I76
J 2
(-650 3150);
DISPLAY 0.723404 (-650 3150);
DISPLAY INVISIBLE (-650 3150);
FORCEADD Q_CAP_DIFFBUS..2
R 2
(-650 3100);
FORCEPROP 1 LAST LOCATION C843
J 2
(-416 3117);
DISPLAY 0.723404 (-416 3117);
PAINT GREEN (-416 3117);
FORCEPROP 2 LAST $SEC 1
J 2
(-475 3175);
DISPLAY 0.680851 (-475 3175);
PAINT MONO (-475 3175);
DISPLAY INVISIBLE (-475 3175);
FORCEPROP 2 LAST CDS_SEC 1
J 2
(-475 3175);
DISPLAY 0.680851 (-475 3175);
DISPLAY INVISIBLE (-475 3175);
FORCEPROP 2 LASTPIN (-575 3100) $PN 1
J 0
(-565 3110);
DISPLAY 0.808511 (-565 3110);
FORCEPROP 2 LASTPIN (-725 3100) $PN 2
J 2
(-735 3110);
DISPLAY 0.808511 (-735 3110);
FORCEPROP 2 LAST VALUE DIFF BUS_0.22UF
J 2
(-800 3100);
DISPLAY 0.553191 (-800 3100);
FORCEPROP 2 LAST TOLERANCE 20%
J 2
(-725 3150);
DISPLAY 0.553191 (-725 3150);
DISPLAY INVISIBLE (-725 3150);
FORCEPROP 2 LAST PACK_TYPE C0201
J 2
(-825 3150);
DISPLAY 0.553191 (-825 3150);
DISPLAY INVISIBLE (-825 3150);
FORCEPROP 1 LAST MATERIAL X6S
J 2
(-641 3179);
DISPLAY 0.574468 (-641 3179);
PAINT GREEN (-641 3179);
DISPLAY INVISIBLE (-641 3179);
FORCEPROP 2 LAST VOLTAGE 6.3V
J 2
(-1000 3150);
DISPLAY 0.553191 (-1000 3150);
DISPLAY INVISIBLE (-1000 3150);
FORCEPROP 1 LAST PIN_NAMES_ROTATE TRUE
J 2
(-650 3100);
DISPLAY 0.489362 (-650 3100);
PAINT GREEN (-650 3100);
DISPLAY INVISIBLE (-650 3100);
FORCEPROP 2 LAST CDS_LIB pure_quanta
J 2
(-650 3100);
DISPLAY INVISIBLE (-650 3100);
FORCEPROP 1 LAST CDS_LMAN_SYM_OUTLINE -25,50,25,-50
J 2
(-650 3100);
DISPLAY 0.468085 (-650 3100);
PAINT GREEN (-650 3100);
DISPLAY INVISIBLE (-650 3100);
FORCEPROP 1 LAST PART_NUMBER SP_CH4221MEE01
J 2
(-766 3188);
DISPLAY 0.574468 (-766 3188);
PAINT GREEN (-766 3188);
DISPLAY INVISIBLE (-766 3188);
FORCEPROP 1 LAST LOCATION C843
J 0
(-400 3175);
DISPLAY 1.021277 (-400 3175);
DISPLAY INVISIBLE (-400 3175);
FORCEPROP 1 LAST PATH I77
J 2
(-650 3100);
DISPLAY 0.723404 (-650 3100);
DISPLAY INVISIBLE (-650 3100);
FORCEADD Q_CAP_DIFFBUS..2
R 2
(-650 3300);
FORCEPROP 1 LAST LOCATION C841
J 2
(-416 3317);
DISPLAY 0.723404 (-416 3317);
PAINT GREEN (-416 3317);
FORCEPROP 2 LAST $SEC 1
J 2
(-475 3375);
DISPLAY 0.680851 (-475 3375);
PAINT MONO (-475 3375);
DISPLAY INVISIBLE (-475 3375);
FORCEPROP 2 LAST CDS_SEC 1
J 2
(-475 3375);
DISPLAY 0.680851 (-475 3375);
DISPLAY INVISIBLE (-475 3375);
FORCEPROP 2 LASTPIN (-575 3300) $PN 1
J 0
(-565 3310);
DISPLAY 0.808511 (-565 3310);
FORCEPROP 2 LASTPIN (-725 3300) $PN 2
J 2
(-735 3310);
DISPLAY 0.808511 (-735 3310);
FORCEPROP 2 LAST VALUE DIFF BUS_0.22UF
J 2
(-800 3300);
DISPLAY 0.553191 (-800 3300);
FORCEPROP 2 LAST TOLERANCE 20%
J 2
(-725 3350);
DISPLAY 0.553191 (-725 3350);
DISPLAY INVISIBLE (-725 3350);
FORCEPROP 2 LAST PACK_TYPE C0201
J 2
(-825 3350);
DISPLAY 0.553191 (-825 3350);
DISPLAY INVISIBLE (-825 3350);
FORCEPROP 1 LAST MATERIAL X6S
J 2
(-641 3379);
DISPLAY 0.574468 (-641 3379);
PAINT GREEN (-641 3379);
DISPLAY INVISIBLE (-641 3379);
FORCEPROP 2 LAST VOLTAGE 6.3V
J 2
(-1000 3350);
DISPLAY 0.553191 (-1000 3350);
DISPLAY INVISIBLE (-1000 3350);
FORCEPROP 1 LAST PIN_NAMES_ROTATE TRUE
J 2
(-650 3300);
DISPLAY 0.489362 (-650 3300);
PAINT GREEN (-650 3300);
DISPLAY INVISIBLE (-650 3300);
FORCEPROP 2 LAST CDS_LIB pure_quanta
J 2
(-650 3300);
DISPLAY INVISIBLE (-650 3300);
FORCEPROP 1 LAST CDS_LMAN_SYM_OUTLINE -25,50,25,-50
J 2
(-650 3300);
DISPLAY 0.468085 (-650 3300);
PAINT GREEN (-650 3300);
DISPLAY INVISIBLE (-650 3300);
FORCEPROP 1 LAST PART_NUMBER SP_CH4221MEE01
J 2
(-766 3388);
DISPLAY 0.574468 (-766 3388);
PAINT GREEN (-766 3388);
DISPLAY INVISIBLE (-766 3388);
FORCEPROP 1 LAST LOCATION C841
J 0
(-400 3375);
DISPLAY 1.021277 (-400 3375);
DISPLAY INVISIBLE (-400 3375);
FORCEPROP 1 LAST PATH I78
J 2
(-650 3300);
DISPLAY 0.723404 (-650 3300);
DISPLAY INVISIBLE (-650 3300);
FORCEADD Q_CAP_DIFFBUS..2
R 2
(-650 3350);
FORCEPROP 1 LAST LOCATION C840
J 2
(-416 3367);
DISPLAY 0.723404 (-416 3367);
PAINT GREEN (-416 3367);
FORCEPROP 2 LAST $SEC 1
J 2
(-475 3425);
DISPLAY 0.680851 (-475 3425);
PAINT MONO (-475 3425);
DISPLAY INVISIBLE (-475 3425);
FORCEPROP 2 LAST CDS_SEC 1
J 2
(-475 3425);
DISPLAY 0.680851 (-475 3425);
DISPLAY INVISIBLE (-475 3425);
FORCEPROP 2 LASTPIN (-575 3350) $PN 1
J 0
(-565 3360);
DISPLAY 0.808511 (-565 3360);
FORCEPROP 2 LASTPIN (-725 3350) $PN 2
J 2
(-735 3360);
DISPLAY 0.808511 (-735 3360);
FORCEPROP 2 LAST VALUE DIFF BUS_0.22UF
J 2
(-800 3350);
DISPLAY 0.553191 (-800 3350);
FORCEPROP 2 LAST TOLERANCE 20%
J 2
(-725 3400);
DISPLAY 0.553191 (-725 3400);
DISPLAY INVISIBLE (-725 3400);
FORCEPROP 2 LAST PACK_TYPE C0201
J 2
(-825 3400);
DISPLAY 0.553191 (-825 3400);
DISPLAY INVISIBLE (-825 3400);
FORCEPROP 1 LAST MATERIAL X6S
J 2
(-641 3429);
DISPLAY 0.574468 (-641 3429);
PAINT GREEN (-641 3429);
DISPLAY INVISIBLE (-641 3429);
FORCEPROP 2 LAST VOLTAGE 6.3V
J 2
(-1000 3400);
DISPLAY 0.553191 (-1000 3400);
DISPLAY INVISIBLE (-1000 3400);
FORCEPROP 1 LAST PIN_NAMES_ROTATE TRUE
J 2
(-650 3350);
DISPLAY 0.489362 (-650 3350);
PAINT GREEN (-650 3350);
DISPLAY INVISIBLE (-650 3350);
FORCEPROP 2 LAST CDS_LIB pure_quanta
J 2
(-650 3350);
DISPLAY INVISIBLE (-650 3350);
FORCEPROP 1 LAST CDS_LMAN_SYM_OUTLINE -25,50,25,-50
J 2
(-650 3350);
DISPLAY 0.468085 (-650 3350);
PAINT GREEN (-650 3350);
DISPLAY INVISIBLE (-650 3350);
FORCEPROP 1 LAST PART_NUMBER SP_CH4221MEE01
J 2
(-766 3438);
DISPLAY 0.574468 (-766 3438);
PAINT GREEN (-766 3438);
DISPLAY INVISIBLE (-766 3438);
FORCEPROP 1 LAST LOCATION C840
J 0
(-400 3425);
DISPLAY 1.021277 (-400 3425);
DISPLAY INVISIBLE (-400 3425);
FORCEPROP 1 LAST PATH I79
J 2
(-650 3350);
DISPLAY 0.723404 (-650 3350);
DISPLAY INVISIBLE (-650 3350);
FORCEADD TAP..1
R 2
(-1625 725);
FORCEPROP 3 LASTPIN (-1575 725) SIG_NAME P5E_CPU0_P2_TX_DP<3>
J 0
(-1565 735);
DISPLAY 0.659574 (-1565 735);
PAINT MONO (-1565 735);
DISPLAY INVISIBLE (-1565 735);
FORCEPROP 1 LASTPIN (-1575 725) BN 3
J 2
(-1563 733);
DISPLAY 0.680851 (-1563 733);
PAINT GREEN (-1563 733);
FORCEPROP 2 LAST CDS_LIB standard
J 0
(-1625 725);
DISPLAY INVISIBLE (-1625 725);
FORCEPROP 1 LAST BODY_TYPE PLUMBING
J 2
(-1625 775);
DISPLAY 0.872340 (-1625 775);
PAINT GREEN (-1625 775);
DISPLAY INVISIBLE (-1625 775);
FORCEPROP 1 LAST HDL_TAP TRUE
J 2
(-1950 600);
DISPLAY 0.872340 (-1950 600);
DISPLAY INVISIBLE (-1950 600);
FORCEPROP 1 LAST PATH I8
J 2
(-1623 725);
DISPLAY 0.872340 (-1623 725);
PAINT GREEN (-1623 725);
DISPLAY INVISIBLE (-1623 725);
FORCEADD Q_CAP_DIFFBUS..2
R 2
(-650 3550);
FORCEPROP 1 LAST LOCATION C838
J 2
(-416 3567);
DISPLAY 0.723404 (-416 3567);
PAINT GREEN (-416 3567);
FORCEPROP 2 LAST $SEC 1
J 2
(-475 3625);
DISPLAY 0.680851 (-475 3625);
PAINT MONO (-475 3625);
DISPLAY INVISIBLE (-475 3625);
FORCEPROP 2 LAST CDS_SEC 1
J 2
(-475 3625);
DISPLAY 0.680851 (-475 3625);
DISPLAY INVISIBLE (-475 3625);
FORCEPROP 2 LASTPIN (-575 3550) $PN 1
J 0
(-565 3560);
DISPLAY 0.808511 (-565 3560);
FORCEPROP 2 LASTPIN (-725 3550) $PN 2
J 2
(-735 3560);
DISPLAY 0.808511 (-735 3560);
FORCEPROP 2 LAST VALUE DIFF BUS_0.22UF
J 2
(-800 3550);
DISPLAY 0.553191 (-800 3550);
FORCEPROP 2 LAST PACK_TYPE C0201
J 2
(-700 3700);
DISPLAY 0.553191 (-700 3700);
PAINT GREEN (-700 3700);
FORCEPROP 2 LAST TOLERANCE 20%
J 2
(-600 3700);
DISPLAY 0.553191 (-600 3700);
PAINT GREEN (-600 3700);
FORCEPROP 1 LAST MATERIAL X6S
J 2
(-741 3754);
DISPLAY 0.574468 (-741 3754);
PAINT GREEN (-741 3754);
FORCEPROP 2 LAST VOLTAGE 6.3V
J 2
(-475 3700);
DISPLAY 0.553191 (-475 3700);
PAINT GREEN (-475 3700);
FORCEPROP 1 LAST PIN_NAMES_ROTATE TRUE
J 2
(-650 3550);
DISPLAY 0.489362 (-650 3550);
PAINT GREEN (-650 3550);
DISPLAY INVISIBLE (-650 3550);
FORCEPROP 1 LAST CDS_LMAN_SYM_OUTLINE -25,50,25,-50
J 2
(-650 3550);
DISPLAY 0.468085 (-650 3550);
PAINT GREEN (-650 3550);
DISPLAY INVISIBLE (-650 3550);
FORCEPROP 2 LAST CDS_LIB pure_quanta
J 2
(-650 3550);
DISPLAY INVISIBLE (-650 3550);
FORCEPROP 1 LAST PART_NUMBER SP_CH4221MEE01
J 2
(-466 3638);
DISPLAY 0.574468 (-466 3638);
PAINT GREEN (-466 3638);
DISPLAY INVISIBLE (-466 3638);
FORCEPROP 1 LAST LOCATION C838
J 0
(-400 3625);
DISPLAY 1.021277 (-400 3625);
DISPLAY INVISIBLE (-400 3625);
FORCEPROP 1 LAST PATH I80
J 2
(-650 3550);
DISPLAY 0.723404 (-650 3550);
DISPLAY INVISIBLE (-650 3550);
FORCEADD Q_CAP_DIFFBUS..2
R 2
(-650 3500);
FORCEPROP 1 LAST LOCATION C839
J 2
(-416 3517);
DISPLAY 0.723404 (-416 3517);
PAINT GREEN (-416 3517);
FORCEPROP 2 LAST $SEC 1
J 2
(-475 3575);
DISPLAY 0.680851 (-475 3575);
PAINT MONO (-475 3575);
DISPLAY INVISIBLE (-475 3575);
FORCEPROP 2 LAST CDS_SEC 1
J 2
(-475 3575);
DISPLAY 0.680851 (-475 3575);
DISPLAY INVISIBLE (-475 3575);
FORCEPROP 2 LASTPIN (-575 3500) $PN 1
J 0
(-565 3510);
DISPLAY 0.808511 (-565 3510);
FORCEPROP 2 LASTPIN (-725 3500) $PN 2
J 2
(-735 3510);
DISPLAY 0.808511 (-735 3510);
FORCEPROP 2 LAST VALUE DIFF BUS_0.22UF
J 2
(-800 3500);
DISPLAY 0.553191 (-800 3500);
FORCEPROP 2 LAST TOLERANCE 20%
J 2
(-725 3550);
DISPLAY 0.553191 (-725 3550);
DISPLAY INVISIBLE (-725 3550);
FORCEPROP 2 LAST PACK_TYPE C0201
J 2
(-825 3550);
DISPLAY 0.553191 (-825 3550);
DISPLAY INVISIBLE (-825 3550);
FORCEPROP 1 LAST MATERIAL X6S
J 2
(-641 3579);
DISPLAY 0.574468 (-641 3579);
PAINT GREEN (-641 3579);
DISPLAY INVISIBLE (-641 3579);
FORCEPROP 2 LAST VOLTAGE 6.3V
J 2
(-1000 3550);
DISPLAY 0.553191 (-1000 3550);
DISPLAY INVISIBLE (-1000 3550);
FORCEPROP 1 LAST PIN_NAMES_ROTATE TRUE
J 2
(-650 3500);
DISPLAY 0.489362 (-650 3500);
PAINT GREEN (-650 3500);
DISPLAY INVISIBLE (-650 3500);
FORCEPROP 2 LAST CDS_LIB pure_quanta
J 2
(-650 3500);
DISPLAY INVISIBLE (-650 3500);
FORCEPROP 1 LAST CDS_LMAN_SYM_OUTLINE -25,50,25,-50
J 2
(-650 3500);
DISPLAY 0.468085 (-650 3500);
PAINT GREEN (-650 3500);
DISPLAY INVISIBLE (-650 3500);
FORCEPROP 1 LAST PART_NUMBER SP_CH4221MEE01
J 2
(-766 3588);
DISPLAY 0.574468 (-766 3588);
PAINT GREEN (-766 3588);
DISPLAY INVISIBLE (-766 3588);
FORCEPROP 1 LAST LOCATION C839
J 0
(-400 3575);
DISPLAY 1.021277 (-400 3575);
DISPLAY INVISIBLE (-400 3575);
FORCEPROP 1 LAST PATH I81
J 2
(-650 3500);
DISPLAY 0.723404 (-650 3500);
DISPLAY INVISIBLE (-650 3500);
FORCEADD TAP..1
(-100 3550);
FORCEPROP 3 LASTPIN (-150 3550) SIG_NAME P5E_CPU0_P2_TX_C_DN<15>
J 0
(-140 3560);
DISPLAY 0.659574 (-140 3560);
PAINT MONO (-140 3560);
DISPLAY INVISIBLE (-140 3560);
FORCEPROP 1 LASTPIN (-150 3550) BN 15
J 0
(-162 3558);
DISPLAY 0.680851 (-162 3558);
PAINT GREEN (-162 3558);
FORCEPROP 2 LAST CDS_LIB standard
J 0
(-100 3550);
DISPLAY INVISIBLE (-100 3550);
FORCEPROP 1 LAST BODY_TYPE PLUMBING
J 0
(-100 3600);
DISPLAY 0.872340 (-100 3600);
PAINT GREEN (-100 3600);
DISPLAY INVISIBLE (-100 3600);
FORCEPROP 1 LAST HDL_TAP TRUE
J 0
(225 3425);
DISPLAY 0.872340 (225 3425);
DISPLAY INVISIBLE (225 3425);
FORCEPROP 1 LAST PATH I82
J 0
(-102 3550);
DISPLAY 0.872340 (-102 3550);
PAINT GREEN (-102 3550);
DISPLAY INVISIBLE (-102 3550);
FORCEADD TAP..1
(-100 3350);
FORCEPROP 3 LASTPIN (-150 3350) SIG_NAME P5E_CPU0_P2_TX_C_DN<14>
J 0
(-140 3360);
DISPLAY 0.659574 (-140 3360);
PAINT MONO (-140 3360);
DISPLAY INVISIBLE (-140 3360);
FORCEPROP 1 LASTPIN (-150 3350) BN 14
J 0
(-162 3358);
DISPLAY 0.680851 (-162 3358);
PAINT GREEN (-162 3358);
FORCEPROP 2 LAST CDS_LIB standard
J 0
(-100 3350);
DISPLAY INVISIBLE (-100 3350);
FORCEPROP 1 LAST BODY_TYPE PLUMBING
J 0
(-100 3400);
DISPLAY 0.872340 (-100 3400);
PAINT GREEN (-100 3400);
DISPLAY INVISIBLE (-100 3400);
FORCEPROP 1 LAST HDL_TAP TRUE
J 0
(225 3225);
DISPLAY 0.872340 (225 3225);
DISPLAY INVISIBLE (225 3225);
FORCEPROP 1 LAST PATH I83
J 0
(-102 3350);
DISPLAY 0.872340 (-102 3350);
PAINT GREEN (-102 3350);
DISPLAY INVISIBLE (-102 3350);
FORCEADD TAP..1
(-100 3150);
FORCEPROP 3 LASTPIN (-150 3150) SIG_NAME P5E_CPU0_P2_TX_C_DN<13>
J 0
(-140 3160);
DISPLAY 0.659574 (-140 3160);
PAINT MONO (-140 3160);
DISPLAY INVISIBLE (-140 3160);
FORCEPROP 1 LASTPIN (-150 3150) BN 13
J 0
(-162 3158);
DISPLAY 0.680851 (-162 3158);
PAINT GREEN (-162 3158);
FORCEPROP 2 LAST CDS_LIB standard
J 0
(-100 3150);
DISPLAY INVISIBLE (-100 3150);
FORCEPROP 1 LAST BODY_TYPE PLUMBING
J 0
(-100 3200);
DISPLAY 0.872340 (-100 3200);
PAINT GREEN (-100 3200);
DISPLAY INVISIBLE (-100 3200);
FORCEPROP 1 LAST HDL_TAP TRUE
J 0
(225 3025);
DISPLAY 0.872340 (225 3025);
DISPLAY INVISIBLE (225 3025);
FORCEPROP 1 LAST PATH I84
J 0
(-102 3150);
DISPLAY 0.872340 (-102 3150);
PAINT GREEN (-102 3150);
DISPLAY INVISIBLE (-102 3150);
FORCEADD TAP..1
(100 125);
FORCEPROP 3 LASTPIN (50 125) SIG_NAME P5E_CPU0_P2_TX_C_DP<0>
J 0
(60 135);
DISPLAY 0.659574 (60 135);
PAINT MONO (60 135);
DISPLAY INVISIBLE (60 135);
FORCEPROP 1 LASTPIN (50 125) BN 0
J 0
(38 133);
DISPLAY 0.680851 (38 133);
PAINT GREEN (38 133);
FORCEPROP 2 LAST CDS_LIB standard
J 0
(100 125);
DISPLAY INVISIBLE (100 125);
FORCEPROP 1 LAST BODY_TYPE PLUMBING
J 0
(100 175);
DISPLAY 0.872340 (100 175);
PAINT GREEN (100 175);
DISPLAY INVISIBLE (100 175);
FORCEPROP 1 LAST HDL_TAP TRUE
J 0
(425 0);
DISPLAY 0.872340 (425 0);
DISPLAY INVISIBLE (425 0);
FORCEPROP 1 LAST PATH I85
J 0
(98 125);
DISPLAY 0.872340 (98 125);
PAINT GREEN (98 125);
DISPLAY INVISIBLE (98 125);
FORCEADD TAP..1
(100 325);
FORCEPROP 3 LASTPIN (50 325) SIG_NAME P5E_CPU0_P2_TX_C_DP<1>
J 0
(60 335);
DISPLAY 0.659574 (60 335);
PAINT MONO (60 335);
DISPLAY INVISIBLE (60 335);
FORCEPROP 1 LASTPIN (50 325) BN 1
J 0
(38 333);
DISPLAY 0.680851 (38 333);
PAINT GREEN (38 333);
FORCEPROP 2 LAST CDS_LIB standard
J 0
(100 325);
DISPLAY INVISIBLE (100 325);
FORCEPROP 1 LAST BODY_TYPE PLUMBING
J 0
(100 375);
DISPLAY 0.872340 (100 375);
PAINT GREEN (100 375);
DISPLAY INVISIBLE (100 375);
FORCEPROP 1 LAST HDL_TAP TRUE
J 0
(425 200);
DISPLAY 0.872340 (425 200);
DISPLAY INVISIBLE (425 200);
FORCEPROP 1 LAST PATH I86
J 0
(98 325);
DISPLAY 0.872340 (98 325);
PAINT GREEN (98 325);
DISPLAY INVISIBLE (98 325);
FORCEADD TAP..1
(100 525);
FORCEPROP 3 LASTPIN (50 525) SIG_NAME P5E_CPU0_P2_TX_C_DP<2>
J 0
(60 535);
DISPLAY 0.659574 (60 535);
PAINT MONO (60 535);
DISPLAY INVISIBLE (60 535);
FORCEPROP 1 LASTPIN (50 525) BN 2
J 0
(38 533);
DISPLAY 0.680851 (38 533);
PAINT GREEN (38 533);
FORCEPROP 2 LAST CDS_LIB standard
J 0
(100 525);
DISPLAY INVISIBLE (100 525);
FORCEPROP 1 LAST BODY_TYPE PLUMBING
J 0
(100 575);
DISPLAY 0.872340 (100 575);
PAINT GREEN (100 575);
DISPLAY INVISIBLE (100 575);
FORCEPROP 1 LAST HDL_TAP TRUE
J 0
(425 400);
DISPLAY 0.872340 (425 400);
DISPLAY INVISIBLE (425 400);
FORCEPROP 1 LAST PATH I87
J 0
(98 525);
DISPLAY 0.872340 (98 525);
PAINT GREEN (98 525);
DISPLAY INVISIBLE (98 525);
FORCEADD TAP..1
(100 725);
FORCEPROP 3 LASTPIN (50 725) SIG_NAME P5E_CPU0_P2_TX_C_DP<3>
J 0
(60 735);
DISPLAY 0.659574 (60 735);
PAINT MONO (60 735);
DISPLAY INVISIBLE (60 735);
FORCEPROP 1 LASTPIN (50 725) BN 3
J 0
(38 733);
DISPLAY 0.680851 (38 733);
PAINT GREEN (38 733);
FORCEPROP 2 LAST CDS_LIB standard
J 0
(100 725);
DISPLAY INVISIBLE (100 725);
FORCEPROP 1 LAST BODY_TYPE PLUMBING
J 0
(100 775);
DISPLAY 0.872340 (100 775);
PAINT GREEN (100 775);
DISPLAY INVISIBLE (100 775);
FORCEPROP 1 LAST HDL_TAP TRUE
J 0
(425 600);
DISPLAY 0.872340 (425 600);
DISPLAY INVISIBLE (425 600);
FORCEPROP 1 LAST PATH I88
J 0
(98 725);
DISPLAY 0.872340 (98 725);
PAINT GREEN (98 725);
DISPLAY INVISIBLE (98 725);
FORCEADD TAP..1
(100 925);
FORCEPROP 3 LASTPIN (50 925) SIG_NAME P5E_CPU0_P2_TX_C_DP<4>
J 0
(60 935);
DISPLAY 0.659574 (60 935);
PAINT MONO (60 935);
DISPLAY INVISIBLE (60 935);
FORCEPROP 1 LASTPIN (50 925) BN 4
J 0
(38 933);
DISPLAY 0.680851 (38 933);
PAINT GREEN (38 933);
FORCEPROP 2 LAST CDS_LIB standard
J 0
(100 925);
DISPLAY INVISIBLE (100 925);
FORCEPROP 1 LAST BODY_TYPE PLUMBING
J 0
(100 975);
DISPLAY 0.872340 (100 975);
PAINT GREEN (100 975);
DISPLAY INVISIBLE (100 975);
FORCEPROP 1 LAST HDL_TAP TRUE
J 0
(425 800);
DISPLAY 0.872340 (425 800);
DISPLAY INVISIBLE (425 800);
FORCEPROP 1 LAST PATH I89
J 0
(98 925);
DISPLAY 0.872340 (98 925);
PAINT GREEN (98 925);
DISPLAY INVISIBLE (98 925);
FORCEADD TAP..1
R 2
(-1625 925);
FORCEPROP 3 LASTPIN (-1575 925) SIG_NAME P5E_CPU0_P2_TX_DP<4>
J 0
(-1565 935);
DISPLAY 0.659574 (-1565 935);
PAINT MONO (-1565 935);
DISPLAY INVISIBLE (-1565 935);
FORCEPROP 1 LASTPIN (-1575 925) BN 4
J 2
(-1563 933);
DISPLAY 0.680851 (-1563 933);
PAINT GREEN (-1563 933);
FORCEPROP 2 LAST CDS_LIB standard
J 0
(-1625 925);
DISPLAY INVISIBLE (-1625 925);
FORCEPROP 1 LAST BODY_TYPE PLUMBING
J 2
(-1625 975);
DISPLAY 0.872340 (-1625 975);
PAINT GREEN (-1625 975);
DISPLAY INVISIBLE (-1625 975);
FORCEPROP 1 LAST HDL_TAP TRUE
J 2
(-1950 800);
DISPLAY 0.872340 (-1950 800);
DISPLAY INVISIBLE (-1950 800);
FORCEPROP 1 LAST PATH I9
J 2
(-1623 925);
DISPLAY 0.872340 (-1623 925);
PAINT GREEN (-1623 925);
DISPLAY INVISIBLE (-1623 925);
FORCEADD TAP..1
(100 1125);
FORCEPROP 3 LASTPIN (50 1125) SIG_NAME P5E_CPU0_P2_TX_C_DP<5>
J 0
(60 1135);
DISPLAY 0.659574 (60 1135);
PAINT MONO (60 1135);
DISPLAY INVISIBLE (60 1135);
FORCEPROP 1 LASTPIN (50 1125) BN 5
J 0
(38 1133);
DISPLAY 0.680851 (38 1133);
PAINT GREEN (38 1133);
FORCEPROP 2 LAST CDS_LIB standard
J 0
(100 1125);
DISPLAY INVISIBLE (100 1125);
FORCEPROP 1 LAST BODY_TYPE PLUMBING
J 0
(100 1175);
DISPLAY 0.872340 (100 1175);
PAINT GREEN (100 1175);
DISPLAY INVISIBLE (100 1175);
FORCEPROP 1 LAST HDL_TAP TRUE
J 0
(425 1000);
DISPLAY 0.872340 (425 1000);
DISPLAY INVISIBLE (425 1000);
FORCEPROP 1 LAST PATH I90
J 0
(98 1125);
DISPLAY 0.872340 (98 1125);
PAINT GREEN (98 1125);
DISPLAY INVISIBLE (98 1125);
FORCEADD TAP..1
(100 1325);
FORCEPROP 3 LASTPIN (50 1325) SIG_NAME P5E_CPU0_P2_TX_C_DP<6>
J 0
(60 1335);
DISPLAY 0.659574 (60 1335);
PAINT MONO (60 1335);
DISPLAY INVISIBLE (60 1335);
FORCEPROP 1 LASTPIN (50 1325) BN 6
J 0
(38 1333);
DISPLAY 0.680851 (38 1333);
PAINT GREEN (38 1333);
FORCEPROP 2 LAST CDS_LIB standard
J 0
(100 1325);
DISPLAY INVISIBLE (100 1325);
FORCEPROP 1 LAST BODY_TYPE PLUMBING
J 0
(100 1375);
DISPLAY 0.872340 (100 1375);
PAINT GREEN (100 1375);
DISPLAY INVISIBLE (100 1375);
FORCEPROP 1 LAST HDL_TAP TRUE
J 0
(425 1200);
DISPLAY 0.872340 (425 1200);
DISPLAY INVISIBLE (425 1200);
FORCEPROP 1 LAST PATH I91
J 0
(98 1325);
DISPLAY 0.872340 (98 1325);
PAINT GREEN (98 1325);
DISPLAY INVISIBLE (98 1325);
FORCEADD TAP..1
(100 1525);
FORCEPROP 3 LASTPIN (50 1525) SIG_NAME P5E_CPU0_P2_TX_C_DP<7>
J 0
(60 1535);
DISPLAY 0.659574 (60 1535);
PAINT MONO (60 1535);
DISPLAY INVISIBLE (60 1535);
FORCEPROP 1 LASTPIN (50 1525) BN 7
J 0
(38 1533);
DISPLAY 0.680851 (38 1533);
PAINT GREEN (38 1533);
FORCEPROP 2 LAST CDS_LIB standard
J 0
(100 1525);
DISPLAY INVISIBLE (100 1525);
FORCEPROP 1 LAST BODY_TYPE PLUMBING
J 0
(100 1575);
DISPLAY 0.872340 (100 1575);
PAINT GREEN (100 1575);
DISPLAY INVISIBLE (100 1575);
FORCEPROP 1 LAST HDL_TAP TRUE
J 0
(425 1400);
DISPLAY 0.872340 (425 1400);
DISPLAY INVISIBLE (425 1400);
FORCEPROP 1 LAST PATH I92
J 0
(98 1525);
DISPLAY 0.872340 (98 1525);
PAINT GREEN (98 1525);
DISPLAY INVISIBLE (98 1525);
FORCEADD OFFPAGE..2
(1100 1550);
FORCEPROP 2 LAST $XR0 295 
J 0
(1289 1550);
DISPLAY 0.638298 (1289 1550);
PAINT MONO (1289 1550);
FORCEPROP 2 LAST CDS_LIB standard
J 0
(1100 1550);
DISPLAY INVISIBLE (1100 1550);
FORCEPROP 1 LAST OFFPAGE TRUE
J 0
(1425 1425);
DISPLAY 0.872340 (1425 1425);
DISPLAY INVISIBLE (1425 1425);
FORCEPROP 1 LAST COMMENT_BODY TRUE
J 0
(1055 1455);
DISPLAY 0.872340 (1055 1455);
PAINT GREEN (1055 1455);
DISPLAY INVISIBLE (1055 1455);
FORCEPROP 2 LAST PATH I93
J 0
(1300 1600);
DISPLAY 1.021277 (1300 1600);
DISPLAY INVISIBLE (1300 1600);
FORCEADD OFFPAGE..2
(1100 1600);
FORCEPROP 2 LAST $XR0 295 
J 0
(1289 1600);
DISPLAY 0.638298 (1289 1600);
PAINT MONO (1289 1600);
FORCEPROP 2 LAST CDS_LIB standard
J 0
(1100 1600);
DISPLAY INVISIBLE (1100 1600);
FORCEPROP 1 LAST OFFPAGE TRUE
J 0
(1425 1475);
DISPLAY 0.872340 (1425 1475);
DISPLAY INVISIBLE (1425 1475);
FORCEPROP 1 LAST COMMENT_BODY TRUE
J 0
(1055 1505);
DISPLAY 0.872340 (1055 1505);
PAINT GREEN (1055 1505);
DISPLAY INVISIBLE (1055 1505);
FORCEPROP 2 LAST PATH I94
J 0
(1300 1650);
DISPLAY 1.021277 (1300 1650);
DISPLAY INVISIBLE (1300 1650);
FORCEADD OFFPAGE..1
(1900 1600);
FORCEPROP 2 LAST $XR0 25 
J 0
(1679 1600);
DISPLAY 0.638298 (1679 1600);
PAINT MONO (1679 1600);
FORCEPROP 2 LAST CDS_LIB standard
J 0
(1900 1600);
DISPLAY INVISIBLE (1900 1600);
FORCEPROP 1 LAST OFFPAGE TRUE
J 0
(2225 1475);
DISPLAY 0.872340 (2225 1475);
DISPLAY INVISIBLE (2225 1475);
FORCEPROP 1 LAST COMMENT_BODY TRUE
J 0
(2025 1500);
DISPLAY 0.872340 (2025 1500);
PAINT GREEN (2025 1500);
DISPLAY INVISIBLE (2025 1500);
FORCEPROP 2 LAST PATH I95
J 0
(1650 1650);
DISPLAY 1.021277 (1650 1650);
DISPLAY INVISIBLE (1650 1650);
FORCEADD OFFPAGE..1
(1900 1550);
FORCEPROP 2 LAST $XR0 25 
J 0
(1679 1550);
DISPLAY 0.638298 (1679 1550);
PAINT MONO (1679 1550);
FORCEPROP 2 LAST CDS_LIB standard
J 0
(1900 1550);
DISPLAY INVISIBLE (1900 1550);
FORCEPROP 1 LAST OFFPAGE TRUE
J 0
(2225 1425);
DISPLAY 0.872340 (2225 1425);
DISPLAY INVISIBLE (2225 1425);
FORCEPROP 1 LAST COMMENT_BODY TRUE
J 0
(2025 1450);
DISPLAY 0.872340 (2025 1450);
PAINT GREEN (2025 1450);
DISPLAY INVISIBLE (2025 1450);
FORCEPROP 2 LAST PATH I96
J 0
(1650 1600);
DISPLAY 1.021277 (1650 1600);
DISPLAY INVISIBLE (1650 1600);
FORCEADD TAP..1
(100 2100);
FORCEPROP 3 LASTPIN (50 2100) SIG_NAME P5E_CPU0_P2_TX_C_DP<8>
J 0
(60 2110);
DISPLAY 0.659574 (60 2110);
PAINT MONO (60 2110);
DISPLAY INVISIBLE (60 2110);
FORCEPROP 1 LASTPIN (50 2100) BN 8
J 0
(38 2108);
DISPLAY 0.680851 (38 2108);
PAINT GREEN (38 2108);
FORCEPROP 2 LAST CDS_LIB standard
J 0
(100 2100);
DISPLAY INVISIBLE (100 2100);
FORCEPROP 1 LAST BODY_TYPE PLUMBING
J 0
(100 2150);
DISPLAY 0.872340 (100 2150);
PAINT GREEN (100 2150);
DISPLAY INVISIBLE (100 2150);
FORCEPROP 1 LAST HDL_TAP TRUE
J 0
(425 1975);
DISPLAY 0.872340 (425 1975);
DISPLAY INVISIBLE (425 1975);
FORCEPROP 1 LAST PATH I97
J 0
(98 2100);
DISPLAY 0.872340 (98 2100);
PAINT GREEN (98 2100);
DISPLAY INVISIBLE (98 2100);
FORCEADD TAP..1
(100 2300);
FORCEPROP 3 LASTPIN (50 2300) SIG_NAME P5E_CPU0_P2_TX_C_DP<9>
J 0
(60 2310);
DISPLAY 0.659574 (60 2310);
PAINT MONO (60 2310);
DISPLAY INVISIBLE (60 2310);
FORCEPROP 1 LASTPIN (50 2300) BN 9
J 0
(38 2308);
DISPLAY 0.680851 (38 2308);
PAINT GREEN (38 2308);
FORCEPROP 2 LAST CDS_LIB standard
J 0
(100 2300);
DISPLAY INVISIBLE (100 2300);
FORCEPROP 1 LAST BODY_TYPE PLUMBING
J 0
(100 2350);
DISPLAY 0.872340 (100 2350);
PAINT GREEN (100 2350);
DISPLAY INVISIBLE (100 2350);
FORCEPROP 1 LAST HDL_TAP TRUE
J 0
(425 2175);
DISPLAY 0.872340 (425 2175);
DISPLAY INVISIBLE (425 2175);
FORCEPROP 1 LAST PATH I98
J 0
(98 2300);
DISPLAY 0.872340 (98 2300);
PAINT GREEN (98 2300);
DISPLAY INVISIBLE (98 2300);
FORCEADD TAP..1
(100 2500);
FORCEPROP 3 LASTPIN (50 2500) SIG_NAME P5E_CPU0_P2_TX_C_DP<10>
J 0
(60 2510);
DISPLAY 0.659574 (60 2510);
PAINT MONO (60 2510);
DISPLAY INVISIBLE (60 2510);
FORCEPROP 1 LASTPIN (50 2500) BN 10
J 0
(38 2508);
DISPLAY 0.680851 (38 2508);
PAINT GREEN (38 2508);
FORCEPROP 2 LAST CDS_LIB standard
J 0
(100 2500);
DISPLAY INVISIBLE (100 2500);
FORCEPROP 1 LAST BODY_TYPE PLUMBING
J 0
(100 2550);
DISPLAY 0.872340 (100 2550);
PAINT GREEN (100 2550);
DISPLAY INVISIBLE (100 2550);
FORCEPROP 1 LAST HDL_TAP TRUE
J 0
(425 2375);
DISPLAY 0.872340 (425 2375);
DISPLAY INVISIBLE (425 2375);
FORCEPROP 1 LAST PATH I99
J 0
(98 2500);
DISPLAY 0.872340 (98 2500);
PAINT GREEN (98 2500);
DISPLAY INVISIBLE (98 2500);
FORCEADD QUANTA_TITLE_BLOCK_C..1
(6175 -1700);
FORCEPROP 0 LAST CDS_CON_LAST_MODIFIED Thu Sep 14 16:12:29 2023
J 0
(4290 -1685);
DISPLAY INVISIBLE (4290 -1685);
FORCEPROP 2 LAST CUSTOM_TXT_CDS <XR_PAGE_TITLE>
J 0
(-1715 3550);
DISPLAY 0.638298 (-1715 3550);
PAINT PINK (-1715 3550);
DISPLAY INVISIBLE (-1715 3550);
FORCEPROP 2 LAST CUSTOM_TXT_CDS <CON_LAST_MODIFIED>
J 0
(4290 -1685);
DISPLAY 0.978723 (4290 -1685);
FORCEPROP 2 LAST CUSTOM_TXT_CDS <Q_NUMBER>
J 0
(4772 -1597);
DISPLAY 1.212766 (4772 -1597);
FORCEPROP 2 LAST CUSTOM_TXT_CDS <Q_PROJ>
J 0
(3793 -1598);
DISPLAY 1.212766 (3793 -1598);
FORCEPROP 2 LAST CUSTOM_TXT_CDS <CON_PAGE_NUM> OF <CON_TOTAL_PAGES>
J 0
(5729 -1682);
DISPLAY 0.978723 (5729 -1682);
FORCEPROP 2 LAST CUSTOM_TXT_CDS <Q_REV>
J 0
(5991 -1597);
DISPLAY 1.212766 (5991 -1597);
FORCEPROP 1 LAST CUSTOM_TXT_CDS <NAME_2>
J 0
(3000 -1650);
FORCEPROP 1 LAST CUSTOM_TXT_CDS <NAME_1>
J 0
(3000 -1525);
FORCEPROP 1 LAST Q_TITLE PCIE AC-COUPLE CAPS 2/5
J 0
(-3191 -1674);
DISPLAY 2.446809 (-3191 -1674);
PAINT GREEN (-3191 -1674);
FORCEPROP 2 LAST CDS_LIB pure_quanta
J 0
(6175 -1700);
DISPLAY INVISIBLE (6175 -1700);
FORCEPROP 1 LAST CDS_LMAN_SYM_OUTLINE -9475,6775,100,-125
J 0
(6175 -1700);
DISPLAY 0.468085 (6175 -1700);
PAINT GREEN (6175 -1700);
DISPLAY INVISIBLE (6175 -1700);
FORCEPROP 2 LAST PAGE_BORDER TRUE
J 0
(-1715 3550);
DISPLAY 0.638298 (-1715 3550);
PAINT PINK (-1715 3550);
DISPLAY INVISIBLE (-1715 3550);
FORCEPROP 2 LAST CDS_XR_PAGE_TITLE CR-64 : @T6G_MB_LIB.T6G(SCH_1):PAGE64
J 0
(-1715 3550);
DISPLAY 0.638298 (-1715 3550);
PAINT PINK (-1715 3550);
DISPLAY INVISIBLE (-1715 3550);
FORCEPROP 1 LAST COMMENT_BODY TRUE
J 0
(6187 -1713);
DISPLAY 0.978723 (6187 -1713);
PAINT GREEN (6187 -1713);
DISPLAY INVISIBLE (6187 -1713);
FORCEPROP 1 LAST Q_DEPT CCBU
J 1
(2412 -1651);
DISPLAY 1.957447 (2412 -1651);
PAINT GREEN (2412 -1651);
DISPLAY INVISIBLE (2412 -1651);
WIRE 17 -1 (-50 3575)(1050 3575);
FORCEPROP 2 LAST SIG_NAME P5E_CPU0_P2_TX_C_DN<15:8>
J 0
(215 3585);
DISPLAY 0.680851 (215 3585);
PAINT WHITE (215 3585);
WIRE 17 -1 (150 3525)(1050 3525);
FORCEPROP 2 LAST SIG_NAME P5E_CPU0_P2_TX_C_DP<15:8>
J 0
(215 3535);
DISPLAY 0.680851 (215 3535);
PAINT WHITE (215 3535);
WIRE 17 -1 (-50 3575)(-50 3375);
WIRE 17 -1 (150 3525)(150 3325);
WIRE 17 -1 (-50 3375)(-50 3175);
WIRE 17 -1 (-50 3175)(-50 2975);
WIRE 17 -1 (-50 2775)(-50 2975);
WIRE 17 -1 (150 3325)(150 3125);
WIRE 17 -1 (150 3125)(150 2925);
WIRE 17 -1 (150 2725)(150 2925);
WIRE 17 -1 (-1425 3175)(-1425 2975);
WIRE 17 -1 (-1425 3375)(-1425 3175);
WIRE 17 -1 (-1425 2775)(-1425 2975);
WIRE 17 -1 (-1425 2775)(-1425 2575);
WIRE 17 -1 (-1425 3575)(-1425 3375);
WIRE 17 -1 (-2525 3575)(-1425 3575);
FORCEPROP 2 LAST SIG_NAME P5E_CPU0_P2_TX_DN<15:8>
J 0
(-2510 3585);
DISPLAY 0.680851 (-2510 3585);
PAINT WHITE (-2510 3585);
WIRE 17 -1 (-1675 2925)(-1675 3125);
WIRE 17 -1 (-1675 2725)(-1675 2925);
WIRE 17 -1 (-1675 3125)(-1675 3325);
WIRE 17 -1 (-1675 3325)(-1675 3525);
WIRE 17 -1 (-1675 2525)(-1675 2725);
WIRE 17 -1 (-1675 2325)(-1675 2525);
WIRE 17 -1 (-2525 3525)(-1675 3525);
FORCEPROP 2 LAST SIG_NAME P5E_CPU0_P2_TX_DP<15:8>
J 0
(-2510 3535);
DISPLAY 0.680851 (-2510 3535);
PAINT WHITE (-2510 3535);
WIRE 17 -1 (150 1550)(150 1350);
WIRE 17 -1 (150 1550)(1050 1550);
FORCEPROP 2 LAST SIG_NAME P5E_CPU0_P2_TX_C_DP<7:0>
J 0
(215 1560);
DISPLAY 0.680851 (215 1560);
PAINT WHITE (215 1560);
WIRE 17 -1 (-50 1400)(-50 1200);
WIRE 17 -1 (-50 1600)(-50 1400);
WIRE 17 -1 (-50 1200)(-50 1000);
WIRE 17 -1 (-50 800)(-50 1000);
WIRE 17 -1 (-50 1600)(1050 1600);
FORCEPROP 2 LAST SIG_NAME P5E_CPU0_P2_TX_C_DN<7:0>
J 0
(215 1610);
DISPLAY 0.680851 (215 1610);
PAINT WHITE (215 1610);
WIRE 17 -1 (2800 750)(2800 950);
WIRE 17 -1 (2800 550)(2800 750);
WIRE 17 -1 (2800 950)(2800 1150);
WIRE 17 -1 (2800 1150)(2800 1350);
WIRE 17 -1 (2800 350)(2800 550);
WIRE 17 -1 (2800 150)(2800 350);
WIRE 17 -1 (2800 1350)(2800 1550);
WIRE 17 -1 (1950 1550)(2800 1550);
FORCEPROP 2 LAST SIG_NAME P5E_CPU0_P3_TX_DP<7:0>
J 0
(1990 1560);
DISPLAY 0.680851 (1990 1560);
PAINT WHITE (1990 1560);
WIRE 17 -1 (3050 800)(3050 1000);
WIRE 17 -1 (3050 800)(3050 600);
WIRE 17 -1 (3050 1200)(3050 1000);
WIRE 17 -1 (3050 1400)(3050 1200);
WIRE 17 -1 (3050 600)(3050 400);
WIRE 17 -1 (3050 400)(3050 200);
WIRE 17 -1 (3050 1600)(3050 1400);
WIRE 17 -1 (1950 1600)(3050 1600);
FORCEPROP 2 LAST SIG_NAME P5E_CPU0_P3_TX_DN<7:0>
J 0
(1990 1610);
DISPLAY 0.680851 (1990 1610);
PAINT WHITE (1990 1610);
WIRE 17 -1 (4625 550)(4625 350);
WIRE 17 -1 (4625 750)(4625 550);
WIRE 17 -1 (4625 350)(4625 150);
WIRE 17 -1 (4625 750)(4625 950);
WIRE 17 -1 (4625 1150)(4625 950);
WIRE 17 -1 (4625 1350)(4625 1150);
WIRE 17 -1 (4625 1550)(4625 1350);
WIRE 17 -1 (4625 1550)(5525 1550);
FORCEPROP 2 LAST SIG_NAME P5E_CPU0_P3_TX_C_DP<7:0>
J 0
(4665 1560);
DISPLAY 0.680851 (4665 1560);
PAINT WHITE (4665 1560);
WIRE 17 -1 (4425 400)(4425 200);
WIRE 17 -1 (4425 600)(4425 400);
WIRE 17 -1 (4425 800)(4425 600);
WIRE 17 -1 (4425 800)(4425 1000);
WIRE 17 -1 (4425 1200)(4425 1000);
WIRE 17 -1 (4425 1400)(4425 1200);
WIRE 17 -1 (4425 1600)(4425 1400);
WIRE 17 -1 (4425 1600)(5525 1600);
FORCEPROP 2 LAST SIG_NAME P5E_CPU0_P3_TX_C_DN<7:0>
J 0
(4665 1610);
DISPLAY 0.680851 (4665 1610);
PAINT WHITE (4665 1610);
WIRE 17 -1 (4625 3325)(4625 3125);
WIRE 17 -1 (4625 3525)(4625 3325);
WIRE 17 -1 (4625 3125)(4625 2925);
WIRE 17 -1 (4625 2725)(4625 2925);
WIRE 17 -1 (4625 3525)(5525 3525);
FORCEPROP 2 LAST SIG_NAME P5E_CPU0_P3_TX_C_DP<15:8>
J 0
(4665 3535);
DISPLAY 0.680851 (4665 3535);
PAINT WHITE (4665 3535);
WIRE 17 -1 (4425 3575)(5525 3575);
FORCEPROP 2 LAST SIG_NAME P5E_CPU0_P3_TX_C_DN<15:8>
J 0
(4665 3585);
DISPLAY 0.680851 (4665 3585);
PAINT WHITE (4665 3585);
WIRE 17 -1 (4425 3575)(4425 3375);
WIRE 17 -1 (4625 2725)(4625 2525);
WIRE 17 -1 (4625 2525)(4625 2325);
WIRE 17 -1 (4625 2325)(4625 2125);
WIRE 17 -1 (4425 3175)(4425 2975);
WIRE 17 -1 (4425 3375)(4425 3175);
WIRE 17 -1 (4425 2775)(4425 2975);
WIRE 17 -1 (4425 2775)(4425 2575);
WIRE 17 -1 (4425 2575)(4425 2375);
WIRE 17 -1 (4425 2375)(4425 2175);
WIRE 17 -1 (3050 3575)(3050 3375);
WIRE 17 -1 (1950 3575)(3050 3575);
FORCEPROP 2 LAST SIG_NAME P5E_CPU0_P3_TX_DN<15:8>
J 0
(1990 3585);
DISPLAY 0.680851 (1990 3585);
PAINT WHITE (1990 3585);
WIRE 17 -1 (3050 3375)(3050 3175);
WIRE 17 -1 (3050 3175)(3050 2975);
WIRE 17 -1 (3050 2775)(3050 2975);
WIRE 17 -1 (3050 2375)(3050 2175);
WIRE 17 -1 (3050 2575)(3050 2375);
WIRE 17 -1 (3050 2775)(3050 2575);
WIRE 17 -1 (2800 3125)(2800 3325);
WIRE 17 -1 (2800 2925)(2800 3125);
WIRE 17 -1 (2800 3325)(2800 3525);
WIRE 17 -1 (1950 3525)(2800 3525);
FORCEPROP 2 LAST SIG_NAME P5E_CPU0_P3_TX_DP<15:8>
J 0
(1990 3535);
DISPLAY 0.680851 (1990 3535);
PAINT WHITE (1990 3535);
WIRE 17 -1 (2800 2125)(2800 2325);
WIRE 17 -1 (2800 2325)(2800 2525);
WIRE 17 -1 (2800 2525)(2800 2725);
WIRE 17 -1 (2800 2725)(2800 2925);
WIRE 17 -1 (150 1350)(150 1150);
WIRE 17 -1 (150 1150)(150 950);
WIRE 17 -1 (150 750)(150 950);
WIRE 17 -1 (150 550)(150 350);
WIRE 17 -1 (150 750)(150 550);
WIRE 17 -1 (150 350)(150 150);
WIRE 17 -1 (150 2725)(150 2525);
WIRE 17 -1 (150 2525)(150 2325);
WIRE 17 -1 (150 2325)(150 2125);
WIRE 17 -1 (-50 2775)(-50 2575);
WIRE 17 -1 (-50 2575)(-50 2375);
WIRE 17 -1 (-50 2375)(-50 2175);
WIRE 17 -1 (-1675 2125)(-1675 2325);
WIRE 17 -1 (-1425 2575)(-1425 2375);
WIRE 17 -1 (-1425 2375)(-1425 2175);
WIRE 17 -1 (-50 800)(-50 600);
WIRE 17 -1 (-50 600)(-50 400);
WIRE 17 -1 (-50 400)(-50 200);
WIRE 17 -1 (-1425 600)(-1425 400);
WIRE 17 -1 (-1425 800)(-1425 600);
WIRE 17 -1 (-1425 400)(-1425 200);
WIRE 17 -1 (-1425 800)(-1425 1000);
WIRE 17 -1 (-1425 1200)(-1425 1000);
WIRE 17 -1 (-1425 1400)(-1425 1200);
WIRE 17 -1 (-1425 1600)(-1425 1400);
WIRE 17 -1 (-2525 1600)(-1425 1600);
FORCEPROP 2 LAST SIG_NAME P5E_CPU0_P2_TX_DN<7:0>
J 0
(-2510 1610);
DISPLAY 0.680851 (-2510 1610);
PAINT WHITE (-2510 1610);
WIRE 17 -1 (-1675 950)(-1675 1150);
WIRE 17 -1 (-1675 750)(-1675 950);
WIRE 17 -1 (-1675 1150)(-1675 1350);
WIRE 17 -1 (-1675 1350)(-1675 1550);
WIRE 17 -1 (-1675 550)(-1675 750);
WIRE 17 -1 (-1675 350)(-1675 550);
WIRE 17 -1 (-2525 1550)(-1675 1550);
FORCEPROP 2 LAST SIG_NAME P5E_CPU0_P2_TX_DP<7:0>
J 0
(-2510 1560);
DISPLAY 0.680851 (-2510 1560);
PAINT WHITE (-2510 1560);
WIRE 17 -1 (-1675 150)(-1675 350);
WIRE 16 -1 (3900 2900)(4525 2900);
WIRE 16 -1 (3750 2300)(2900 2300);
WIRE 16 -1 (-575 2300)(50 2300);
WIRE 16 -1 (-725 2150)(-1325 2150);
WIRE 16 -1 (-725 2100)(-1575 2100);
WIRE 16 -1 (-575 2100)(50 2100);
WIRE 16 -1 (-575 2900)(50 2900);
WIRE 16 -1 (-575 2750)(-150 2750);
WIRE 16 -1 (-725 2550)(-1325 2550);
WIRE 16 -1 (-725 2500)(-1575 2500);
WIRE 16 -1 (-725 2300)(-1575 2300);
WIRE 16 -1 (-725 3550)(-1325 3550);
WIRE 16 -1 (-725 3500)(-1575 3500);
WIRE 16 -1 (-725 3300)(-1575 3300);
WIRE 16 -1 (-725 2750)(-1325 2750);
WIRE 16 -1 (-575 975)(-150 975);
WIRE 16 -1 (-575 925)(50 925);
WIRE 16 -1 (-575 375)(-150 375);
WIRE 16 -1 (-575 1525)(50 1525);
WIRE 16 -1 (-575 1575)(-150 1575);
WIRE 16 -1 (-575 125)(50 125);
WIRE 16 -1 (-725 725)(-1575 725);
WIRE 16 -1 (-725 125)(-1575 125);
WIRE 16 -1 (-575 175)(-150 175);
WIRE 16 -1 (-575 725)(50 725);
WIRE 16 -1 (-725 1125)(-1575 1125);
WIRE 16 -1 (-725 975)(-1325 975);
WIRE 16 -1 (-725 575)(-1325 575);
WIRE 16 -1 (-725 525)(-1575 525);
WIRE 16 -1 (-725 325)(-1575 325);
WIRE 16 -1 (-725 1375)(-1325 1375);
WIRE 16 -1 (-725 1525)(-1575 1525);
WIRE 16 -1 (-725 175)(-1325 175);
WIRE 16 -1 (-725 775)(-1325 775);
WIRE 16 -1 (-725 1325)(-1575 1325);
WIRE 16 -1 (-725 1175)(-1325 1175);
WIRE 16 -1 (-725 1575)(-1325 1575);
WIRE 16 -1 (-725 925)(-1575 925);
WIRE 16 -1 (-725 375)(-1325 375);
WIRE 16 -1 (-575 775)(-150 775);
WIRE 16 -1 (-575 575)(-150 575);
WIRE 16 -1 (-575 1375)(-150 1375);
WIRE 16 -1 (-725 2350)(-1325 2350);
WIRE 16 -1 (-725 3150)(-1325 3150);
WIRE 16 -1 (-725 3350)(-1325 3350);
WIRE 16 -1 (-725 2700)(-1575 2700);
WIRE 16 -1 (-725 3100)(-1575 3100);
WIRE 16 -1 (-575 2350)(-150 2350);
WIRE 16 -1 (-575 2150)(-150 2150);
WIRE 16 -1 (-575 2550)(-150 2550);
WIRE 16 -1 (-575 2950)(-150 2950);
WIRE 16 -1 (-575 2500)(50 2500);
WIRE 16 -1 (-575 2700)(50 2700);
WIRE 16 -1 (-575 525)(50 525);
WIRE 16 -1 (-575 325)(50 325);
WIRE 16 -1 (-575 1125)(50 1125);
WIRE 16 -1 (3750 125)(2900 125);
WIRE 16 -1 (3750 1125)(2900 1125);
WIRE 16 -1 (3750 725)(2900 725);
WIRE 16 -1 (3750 325)(2900 325);
WIRE 16 -1 (3750 525)(2900 525);
WIRE 16 -1 (3750 1325)(2900 1325);
WIRE 16 -1 (3750 1525)(2900 1525);
WIRE 16 -1 (3750 375)(3150 375);
WIRE 16 -1 (3750 175)(3150 175);
WIRE 16 -1 (3750 975)(3150 975);
WIRE 16 -1 (3750 1175)(3150 1175);
WIRE 16 -1 (3750 1375)(3150 1375);
WIRE 16 -1 (3750 1575)(3150 1575);
WIRE 16 -1 (3750 2900)(2900 2900);
WIRE 16 -1 (3750 2500)(2900 2500);
WIRE 16 -1 (3750 2700)(2900 2700);
WIRE 16 -1 (3750 2100)(2900 2100);
WIRE 16 -1 (3750 3100)(2900 3100);
WIRE 16 -1 (3750 3500)(2900 3500);
WIRE 16 -1 (3750 3300)(2900 3300);
WIRE 16 -1 (3750 2950)(3150 2950);
WIRE 16 -1 (3750 2550)(3150 2550);
WIRE 16 -1 (3750 2350)(3150 2350);
WIRE 16 -1 (3750 2750)(3150 2750);
WIRE 16 -1 (3750 2150)(3150 2150);
WIRE 16 -1 (3750 3550)(3150 3550);
WIRE 16 -1 (3750 3150)(3150 3150);
WIRE 16 -1 (3750 3350)(3150 3350);
WIRE 16 -1 (3900 3100)(4525 3100);
WIRE 16 -1 (3900 3150)(4325 3150);
WIRE 16 -1 (3900 1125)(4525 1125);
WIRE 16 -1 (3900 1325)(4525 1325);
WIRE 16 -1 (3900 2100)(4525 2100);
WIRE 16 -1 (3900 375)(4325 375);
WIRE 16 -1 (3900 575)(4325 575);
WIRE 16 -1 (3900 775)(4325 775);
WIRE 16 -1 (3900 925)(4525 925);
WIRE 16 -1 (3900 525)(4525 525);
WIRE 16 -1 (3900 725)(4525 725);
WIRE 16 -1 (3900 975)(4325 975);
WIRE 16 -1 (3900 1175)(4325 1175);
WIRE 16 -1 (3900 1375)(4325 1375);
WIRE 16 -1 (3900 1575)(4325 1575);
WIRE 16 -1 (3900 1525)(4525 1525);
WIRE 16 -1 (3900 2350)(4325 2350);
WIRE 16 -1 (3900 2150)(4325 2150);
WIRE 16 -1 (3900 2550)(4325 2550);
WIRE 16 -1 (3900 2750)(4325 2750);
WIRE 16 -1 (3900 2950)(4325 2950);
WIRE 16 -1 (3900 2300)(4525 2300);
WIRE 16 -1 (3900 2500)(4525 2500);
WIRE 16 -1 (3900 2700)(4525 2700);
WIRE 16 -1 (3900 3350)(4325 3350);
WIRE 16 -1 (3900 3550)(4325 3550);
WIRE 16 -1 (3900 3500)(4525 3500);
WIRE 16 -1 (3900 3300)(4525 3300);
WIRE 16 -1 (3900 175)(4325 175);
WIRE 16 -1 (3900 125)(4525 125);
WIRE 16 -1 (3900 325)(4525 325);
WIRE 16 -1 (3750 575)(3150 575);
WIRE 16 -1 (3750 775)(3150 775);
WIRE 16 -1 (3750 925)(2900 925);
WIRE 16 -1 (-575 1175)(-150 1175);
WIRE 16 -1 (-575 1325)(50 1325);
WIRE 16 -1 (-725 2900)(-1575 2900);
WIRE 16 -1 (-725 2950)(-1325 2950);
WIRE 16 -1 (-575 3100)(50 3100);
WIRE 16 -1 (-575 3150)(-150 3150);
WIRE 16 -1 (-575 3300)(50 3300);
WIRE 16 -1 (-575 3350)(-150 3350);
WIRE 16 -1 (-575 3500)(50 3500);
WIRE 16 -1 (-575 3550)(-150 3550);
FORCENOTE
CPU0 PCIE P3 TX
(2550 -500) 0;
DISPLAY LEFT (2550 -500);
DISPLAY 4.148936 (2550 -500);
PAINT WHITE (2550 -500);
FORCENOTE
CPU0 PCIE P2 TX
(-2050 -500) 0;
DISPLAY LEFT (-2050 -500);
DISPLAY 4.148936 (-2050 -500);
PAINT WHITE (-2050 -500);
QUIT
